FILE_TYPE = MACRO_DRAWING;
SET COLOR_WIRE YELLOW;
SET COLOR_PROP MONO;
SET COLOR_DOT WHITE;
SET COLOR_ARC YELLOW;
SET COLOR_BODY GREEN;
SET COLOR_NOTE MONO;
SET PROP_DISPLAY VALUE;
SET PAGE_NUMBER P173;
FORCEADD GND..1
(-1150 1425);
FORCEPROP 3 LASTPIN (-1150 1475) SIG_NAME GND\g
J 0
(-1140 1485);
DISPLAY 0.659574 (-1140 1485);
PAINT MONO (-1140 1485);
DISPLAY INVISIBLE (-1140 1485);
FORCEPROP 1 LAST VOLTAGE 0.0V
J 0
(-1195 1382);
DISPLAY 0.340426 (-1195 1382);
PAINT SKYBLUE (-1195 1382);
DISPLAY INVISIBLE (-1195 1382);
FORCEPROP 2 LAST ROOM ST_SATA
J 0
(-1125 1500);
DISPLAY 1.361702 (-1125 1500);
PAINT ORANGE (-1125 1500);
DISPLAY INVISIBLE (-1125 1500);
FORCEPROP 2 LAST BOM_COST ST_SATA
J 0
(-1125 1500);
DISPLAY 1.361702 (-1125 1500);
PAINT ORANGE (-1125 1500);
DISPLAY INVISIBLE (-1125 1500);
FORCEPROP 1 LAST SIZE 1B
J 0
(-1075 1375);
DISPLAY 1.170213 (-1075 1375);
PAINT AQUA (-1075 1375);
DISPLAY INVISIBLE (-1075 1375);
FORCEPROP 2 LAST CDS_LIB mstr_symbols
J 0
(-1150 1425);
PAINT ORANGE (-1150 1425);
DISPLAY INVISIBLE (-1150 1425);
FORCEPROP 1 LAST PATH I103
J 0
(-1075 1425);
DISPLAY 0.872340 (-1075 1425);
PAINT AQUA (-1075 1425);
DISPLAY INVISIBLE (-1075 1425);
FORCEPROP 1 LAST BODY_TYPE PLUMBING
J 0
(-1195 1382);
DISPLAY 0.340426 (-1195 1382);
PAINT GREEN (-1195 1382);
DISPLAY INVISIBLE (-1195 1382);
FORCEPROP 1 LAST HDL_POWER GND
J 0
(-1150 1575);
DISPLAY 1.170213 (-1150 1575);
PAINT GREEN (-1150 1575);
DISPLAY INVISIBLE (-1150 1575);
FORCEADD GND..1
(-2925 1450);
FORCEPROP 3 LASTPIN (-2925 1500) SIG_NAME GND\g
J 0
(-2915 1510);
DISPLAY 0.659574 (-2915 1510);
PAINT MONO (-2915 1510);
DISPLAY INVISIBLE (-2915 1510);
FORCEPROP 1 LAST VOLTAGE 0.0V
J 0
(-2970 1407);
DISPLAY 0.340426 (-2970 1407);
PAINT SKYBLUE (-2970 1407);
DISPLAY INVISIBLE (-2970 1407);
FORCEPROP 2 LAST ROOM ST_SATA
J 0
(-2900 1525);
DISPLAY 1.361702 (-2900 1525);
PAINT ORANGE (-2900 1525);
DISPLAY INVISIBLE (-2900 1525);
FORCEPROP 1 LAST SIZE 1B
J 0
(-2850 1400);
DISPLAY 1.170213 (-2850 1400);
PAINT AQUA (-2850 1400);
DISPLAY INVISIBLE (-2850 1400);
FORCEPROP 2 LAST BOM_COST ST_SATA
J 0
(-2900 1525);
DISPLAY 1.361702 (-2900 1525);
PAINT ORANGE (-2900 1525);
DISPLAY INVISIBLE (-2900 1525);
FORCEPROP 2 LAST CDS_LIB mstr_symbols
J 0
(-2925 1450);
PAINT ORANGE (-2925 1450);
DISPLAY INVISIBLE (-2925 1450);
FORCEPROP 1 LAST PATH I162
J 0
(-2850 1450);
DISPLAY 0.872340 (-2850 1450);
PAINT AQUA (-2850 1450);
DISPLAY INVISIBLE (-2850 1450);
FORCEPROP 1 LAST BODY_TYPE PLUMBING
J 0
(-2970 1407);
DISPLAY 0.340426 (-2970 1407);
PAINT GREEN (-2970 1407);
DISPLAY INVISIBLE (-2970 1407);
FORCEPROP 1 LAST HDL_POWER GND
J 0
(-2925 1600);
DISPLAY 1.170213 (-2925 1600);
PAINT GREEN (-2925 1600);
DISPLAY INVISIBLE (-2925 1600);
FORCEADD CONN72_G97614002_A..1
(-2025 3100);
FORCEPROP 1 LAST LOCATION J8A1
J 0
(-2675 4700);
DISPLAY 0.617021 (-2675 4700);
PAINT AQUA (-2675 4700);
FORCEPROP 1 LAST PART_NUMBER G97614-002
J 0
(-2675 1425);
DISPLAY 0.617021 (-2675 1425);
PAINT BLUE (-2675 1425);
FORCEPROP 1 LAST MATERIAL CONN
J 0
(-2675 4750);
DISPLAY 0.617021 (-2675 4750);
PAINT SKYBLUE (-2675 4750);
FORCEPROP 2 LASTPIN (-1325 2650) $PN 2C4
J 0
(-1315 2660);
DISPLAY 0.617021 (-1315 2660);
PAINT ORANGE (-1315 2660);
FORCEPROP 2 LASTPIN (-1325 2600) $PN 2C5
J 0
(-1315 2610);
DISPLAY 0.617021 (-1315 2610);
PAINT ORANGE (-1315 2610);
FORCEPROP 2 LASTPIN (-1325 1650) $PN 2D9
J 0
(-1315 1660);
DISPLAY 0.617021 (-1315 1660);
PAINT ORANGE (-1315 1660);
FORCEPROP 2 LASTPIN (-1325 1900) $PN 2D6
J 0
(-1315 1910);
DISPLAY 0.617021 (-1315 1910);
PAINT ORANGE (-1315 1910);
FORCEPROP 2 LASTPIN (-1325 2150) $PN 2D3
J 0
(-1315 2160);
DISPLAY 0.617021 (-1315 2160);
PAINT ORANGE (-1315 2160);
FORCEPROP 2 LASTPIN (-1325 2500) $PN 2C9
J 0
(-1315 2510);
DISPLAY 0.617021 (-1315 2510);
PAINT ORANGE (-1315 2510);
FORCEPROP 2 LASTPIN (-1325 2750) $PN 2C6
J 0
(-1315 2760);
DISPLAY 0.617021 (-1315 2760);
PAINT ORANGE (-1315 2760);
FORCEPROP 2 LASTPIN (-1325 3000) $PN 2C3
J 0
(-1315 3010);
DISPLAY 0.617021 (-1315 3010);
PAINT ORANGE (-1315 3010);
FORCEPROP 2 LASTPIN (-2725 1650) $PN 2B9
J 2
(-2735 1660);
DISPLAY 0.617021 (-2735 1660);
PAINT ORANGE (-2735 1660);
FORCEPROP 2 LASTPIN (-2725 1900) $PN 2B6
J 2
(-2735 1910);
DISPLAY 0.617021 (-2735 1910);
PAINT ORANGE (-2735 1910);
FORCEPROP 2 LASTPIN (-2725 2150) $PN 2B3
J 2
(-2735 2160);
DISPLAY 0.617021 (-2735 2160);
PAINT ORANGE (-2735 2160);
FORCEPROP 2 LASTPIN (-2725 2750) $PN 2A9
J 2
(-2735 2760);
DISPLAY 0.617021 (-2735 2760);
PAINT ORANGE (-2735 2760);
FORCEPROP 2 LASTPIN (-2725 2500) $PN 2A6
J 2
(-2735 2510);
DISPLAY 0.617021 (-2735 2510);
PAINT ORANGE (-2735 2510);
FORCEPROP 2 LASTPIN (-2725 3000) $PN 2A3
J 2
(-2735 3010);
DISPLAY 0.617021 (-2735 3010);
PAINT ORANGE (-2735 3010);
FORCEPROP 2 LASTPIN (-1325 3150) $PN 1D9
J 0
(-1315 3160);
DISPLAY 0.617021 (-1315 3160);
PAINT ORANGE (-1315 3160);
FORCEPROP 2 LASTPIN (-1325 3400) $PN 1D6
J 0
(-1315 3410);
DISPLAY 0.617021 (-1315 3410);
PAINT ORANGE (-1315 3410);
FORCEPROP 2 LASTPIN (-1325 3650) $PN 1D3
J 0
(-1315 3660);
DISPLAY 0.617021 (-1315 3660);
PAINT ORANGE (-1315 3660);
FORCEPROP 2 LASTPIN (-1325 4000) $PN 1C9
J 0
(-1315 4010);
DISPLAY 0.617021 (-1315 4010);
PAINT ORANGE (-1315 4010);
FORCEPROP 2 LASTPIN (-1325 4250) $PN 1C6
J 0
(-1315 4260);
DISPLAY 0.617021 (-1315 4260);
PAINT ORANGE (-1315 4260);
FORCEPROP 2 LASTPIN (-1325 4500) $PN 1C3
J 0
(-1315 4510);
DISPLAY 0.617021 (-1315 4510);
PAINT ORANGE (-1315 4510);
FORCEPROP 2 LASTPIN (-2725 3150) $PN 1B9
J 2
(-2735 3160);
DISPLAY 0.617021 (-2735 3160);
PAINT ORANGE (-2735 3160);
FORCEPROP 2 LASTPIN (-2725 3400) $PN 1B6
J 2
(-2735 3410);
DISPLAY 0.617021 (-2735 3410);
PAINT ORANGE (-2735 3410);
FORCEPROP 2 LASTPIN (-2725 3650) $PN 1B3
J 2
(-2735 3660);
DISPLAY 0.617021 (-2735 3660);
PAINT ORANGE (-2735 3660);
FORCEPROP 2 LASTPIN (-2725 4000) $PN 1A9
J 2
(-2735 4010);
DISPLAY 0.617021 (-2735 4010);
PAINT ORANGE (-2735 4010);
FORCEPROP 2 LASTPIN (-2725 4250) $PN 1A6
J 2
(-2735 4260);
DISPLAY 0.617021 (-2735 4260);
PAINT ORANGE (-2735 4260);
FORCEPROP 2 LASTPIN (-2725 4500) $PN 1A3
J 2
(-2735 4510);
DISPLAY 0.617021 (-2735 4510);
PAINT ORANGE (-2735 4510);
FORCEPROP 2 LASTPIN (-2725 4350) $PN 1B5
J 2
(-2735 4360);
DISPLAY 0.617021 (-2735 4360);
PAINT ORANGE (-2735 4360);
FORCEPROP 2 LASTPIN (-2725 4400) $PN 1B4
J 2
(-2735 4410);
DISPLAY 0.617021 (-2735 4410);
PAINT ORANGE (-2735 4410);
FORCEPROP 2 LASTPIN (-2725 4100) $PN 1A5
J 2
(-2735 4110);
DISPLAY 0.617021 (-2735 4110);
PAINT ORANGE (-2735 4110);
FORCEPROP 2 LASTPIN (-2725 4150) $PN 1A4
J 2
(-2735 4160);
DISPLAY 0.617021 (-2735 4160);
PAINT ORANGE (-2735 4160);
FORCEPROP 2 LASTPIN (-2725 3500) $PN 1B8
J 2
(-2735 3510);
DISPLAY 0.617021 (-2735 3510);
PAINT ORANGE (-2735 3510);
FORCEPROP 2 LASTPIN (-2725 3550) $PN 1B7
J 2
(-2735 3560);
DISPLAY 0.617021 (-2735 3560);
PAINT ORANGE (-2735 3560);
FORCEPROP 2 LASTPIN (-2725 3250) $PN 1A8
J 2
(-2735 3260);
DISPLAY 0.617021 (-2735 3260);
PAINT ORANGE (-2735 3260);
FORCEPROP 2 LASTPIN (-2725 3300) $PN 1A7
J 2
(-2735 3310);
DISPLAY 0.617021 (-2735 3310);
PAINT ORANGE (-2735 3310);
FORCEPROP 2 LASTPIN (-2725 2850) $PN 2B5
J 2
(-2735 2860);
DISPLAY 0.617021 (-2735 2860);
PAINT ORANGE (-2735 2860);
FORCEPROP 2 LASTPIN (-2725 2900) $PN 2B4
J 2
(-2735 2910);
DISPLAY 0.617021 (-2735 2910);
PAINT ORANGE (-2735 2910);
FORCEPROP 2 LASTPIN (-2725 2600) $PN 2A5
J 2
(-2735 2610);
DISPLAY 0.617021 (-2735 2610);
PAINT ORANGE (-2735 2610);
FORCEPROP 2 LASTPIN (-2725 2650) $PN 2A4
J 2
(-2735 2660);
DISPLAY 0.617021 (-2735 2660);
PAINT ORANGE (-2735 2660);
FORCEPROP 2 LASTPIN (-2725 2000) $PN 2B8
J 2
(-2735 2010);
DISPLAY 0.617021 (-2735 2010);
PAINT ORANGE (-2735 2010);
FORCEPROP 2 LASTPIN (-2725 2050) $PN 2B7
J 2
(-2735 2060);
DISPLAY 0.617021 (-2735 2060);
PAINT ORANGE (-2735 2060);
FORCEPROP 2 LASTPIN (-2725 1750) $PN 2A8
J 2
(-2735 1760);
DISPLAY 0.617021 (-2735 1760);
PAINT ORANGE (-2735 1760);
FORCEPROP 2 LASTPIN (-1325 3900) $PN 1A2
J 0
(-1315 3910);
DISPLAY 0.617021 (-1315 3910);
PAINT ORANGE (-1315 3910);
FORCEPROP 2 LASTPIN (-1325 3850) $PN 1B2
J 0
(-1315 3860);
DISPLAY 0.617021 (-1315 3860);
PAINT ORANGE (-1315 3860);
FORCEPROP 2 LASTPIN (-1325 3800) $PN 1C2
J 0
(-1315 3810);
DISPLAY 0.617021 (-1315 3810);
PAINT ORANGE (-1315 3810);
FORCEPROP 2 LASTPIN (-2725 3850) $PN 1B1
J 2
(-2735 3860);
DISPLAY 0.617021 (-2735 3860);
PAINT ORANGE (-2735 3860);
FORCEPROP 2 LASTPIN (-2725 3800) $PN 1C1
J 2
(-2735 3810);
DISPLAY 0.617021 (-2735 3810);
PAINT ORANGE (-2735 3810);
FORCEPROP 2 LASTPIN (-2725 3750) $PN 1D1
J 2
(-2735 3760);
DISPLAY 0.617021 (-2735 3760);
PAINT ORANGE (-2735 3760);
FORCEPROP 2 LASTPIN (-1325 3750) $PN 1D2
J 0
(-1315 3760);
DISPLAY 0.617021 (-1315 3760);
PAINT ORANGE (-1315 3760);
FORCEPROP 2 LASTPIN (-2725 3900) $PN 1A1
J 2
(-2735 3910);
DISPLAY 0.617021 (-2735 3910);
PAINT ORANGE (-2735 3910);
FORCEPROP 2 LASTPIN (-1325 2400) $PN 2A2
J 0
(-1315 2410);
DISPLAY 0.617021 (-1315 2410);
PAINT ORANGE (-1315 2410);
FORCEPROP 2 LASTPIN (-1325 2350) $PN 2B2
J 0
(-1315 2360);
DISPLAY 0.617021 (-1315 2360);
PAINT ORANGE (-1315 2360);
FORCEPROP 2 LASTPIN (-1325 2300) $PN 2C2
J 0
(-1315 2310);
DISPLAY 0.617021 (-1315 2310);
PAINT ORANGE (-1315 2310);
FORCEPROP 2 LASTPIN (-2725 2350) $PN 2B1
J 2
(-2735 2360);
DISPLAY 0.617021 (-2735 2360);
PAINT ORANGE (-2735 2360);
FORCEPROP 2 LASTPIN (-2725 2300) $PN 2C1
J 2
(-2735 2310);
DISPLAY 0.617021 (-2735 2310);
PAINT ORANGE (-2735 2310);
FORCEPROP 2 LASTPIN (-2725 2250) $PN 2D1
J 2
(-2735 2260);
DISPLAY 0.617021 (-2735 2260);
PAINT ORANGE (-2735 2260);
FORCEPROP 2 LASTPIN (-1325 2250) $PN 2D2
J 0
(-1315 2260);
DISPLAY 0.617021 (-1315 2260);
PAINT ORANGE (-1315 2260);
FORCEPROP 2 LASTPIN (-2725 2400) $PN 2A1
J 2
(-2735 2410);
DISPLAY 0.617021 (-2735 2410);
PAINT ORANGE (-2735 2410);
FORCEPROP 2 LASTPIN (-1325 4350) $PN 1D5
J 0
(-1315 4360);
DISPLAY 0.617021 (-1315 4360);
PAINT ORANGE (-1315 4360);
FORCEPROP 2 LASTPIN (-1325 4400) $PN 1D4
J 0
(-1315 4410);
DISPLAY 0.617021 (-1315 4410);
PAINT ORANGE (-1315 4410);
FORCEPROP 2 LASTPIN (-1325 4100) $PN 1C5
J 0
(-1315 4110);
DISPLAY 0.617021 (-1315 4110);
PAINT ORANGE (-1315 4110);
FORCEPROP 2 LASTPIN (-1325 4150) $PN 1C4
J 0
(-1315 4160);
DISPLAY 0.617021 (-1315 4160);
PAINT ORANGE (-1315 4160);
FORCEPROP 2 LASTPIN (-1325 3500) $PN 1D8
J 0
(-1315 3510);
DISPLAY 0.617021 (-1315 3510);
PAINT ORANGE (-1315 3510);
FORCEPROP 2 LASTPIN (-1325 3250) $PN 1C8
J 0
(-1315 3260);
DISPLAY 0.617021 (-1315 3260);
PAINT ORANGE (-1315 3260);
FORCEPROP 2 LASTPIN (-1325 3300) $PN 1C7
J 0
(-1315 3310);
DISPLAY 0.617021 (-1315 3310);
PAINT ORANGE (-1315 3310);
FORCEPROP 2 LASTPIN (-1325 2850) $PN 2D5
J 0
(-1315 2860);
DISPLAY 0.617021 (-1315 2860);
PAINT ORANGE (-1315 2860);
FORCEPROP 2 LASTPIN (-1325 2900) $PN 2D4
J 0
(-1315 2910);
DISPLAY 0.617021 (-1315 2910);
PAINT ORANGE (-1315 2910);
FORCEPROP 2 LASTPIN (-1325 2000) $PN 2D8
J 0
(-1315 2010);
DISPLAY 0.617021 (-1315 2010);
PAINT ORANGE (-1315 2010);
FORCEPROP 2 LASTPIN (-1325 2050) $PN 2D7
J 0
(-1315 2060);
DISPLAY 0.617021 (-1315 2060);
PAINT ORANGE (-1315 2060);
FORCEPROP 2 LASTPIN (-1325 1750) $PN 2C8
J 0
(-1315 1760);
DISPLAY 0.617021 (-1315 1760);
PAINT ORANGE (-1315 1760);
FORCEPROP 2 LASTPIN (-1325 1800) $PN 2C7
J 0
(-1315 1810);
DISPLAY 0.617021 (-1315 1810);
PAINT ORANGE (-1315 1810);
FORCEPROP 2 LASTPIN (-2725 1800) $PN 2A7
J 2
(-2735 1810);
DISPLAY 0.617021 (-2735 1810);
PAINT ORANGE (-2735 1810);
FORCEPROP 2 LASTPIN (-1325 3550) $PN 1D7
J 0
(-1315 3560);
DISPLAY 0.617021 (-1315 3560);
PAINT ORANGE (-1315 3560);
FORCEPROP 1 LAST PACK_TYPE CP
J 0
(-2675 5500);
PAINT SKYBLUE (-2675 5500);
DISPLAY INVISIBLE (-2675 5500);
FORCEPROP 2 LAST ROOM ST_SATA
J 0
(-2625 4750);
DISPLAY 1.361702 (-2625 4750);
PAINT ORANGE (-2625 4750);
DISPLAY INVISIBLE (-2625 4750);
FORCEPROP 1 LAST PATH I163
J 0
(-2025 4700);
PAINT GREEN (-2025 4700);
DISPLAY INVISIBLE (-2025 4700);
FORCEPROP 2 LAST CDS_LOCATION J8A1
J 0
(-2675 4700);
DISPLAY 0.617021 (-2675 4700);
PAINT AQUA (-2675 4700);
DISPLAY INVISIBLE (-2675 4700);
FORCEPROP 2 LAST SEC 1
J 0
(-2025 5450);
DISPLAY 0.680851 (-2025 5450);
PAINT MONO (-2025 5450);
DISPLAY INVISIBLE (-2025 5450);
FORCEPROP 2 LAST SEC_TYPE CP
J 0
(-2025 5450);
DISPLAY 1.021277 (-2025 5450);
PAINT ORANGE (-2025 5450);
DISPLAY INVISIBLE (-2025 5450);
FORCEPROP 2 LAST CDS_LIB mstr_conn
J 0
(-2025 3800);
PAINT ORANGE (-2025 3800);
DISPLAY INVISIBLE (-2025 3800);
FORCEPROP 2 LAST BOM_COST ST_SATA
J 0
(-2625 4750);
DISPLAY 1.361702 (-2625 4750);
PAINT ORANGE (-2625 4750);
DISPLAY INVISIBLE (-2625 4750);
FORCEADD CAP_A..2
(-4900 3550);
FORCEPROP 1 LAST LOCATION C2L13
J 1
(-4900 3650);
DISPLAY 0.617021 (-4900 3650);
PAINT AQUA (-4900 3650);
FORCEPROP 1 LAST PART_NUMBER A36096-045
J 1
(-4900 3600);
DISPLAY 0.617021 (-4900 3600);
PAINT BLUE (-4900 3600);
FORCEPROP 1 LAST VALUE 0.01UF
J 2
(-4900 3450);
DISPLAY 0.617021 (-4900 3450);
PAINT SKYBLUE (-4900 3450);
FORCEPROP 1 LAST TOLERANCE 10%
J 2
(-4900 3400);
DISPLAY 0.617021 (-4900 3400);
PAINT SKYBLUE (-4900 3400);
FORCEPROP 1 LAST PACK_TYPE 0402V
J 1
(-4900 3350);
DISPLAY 0.617021 (-4900 3350);
PAINT SKYBLUE (-4900 3350);
FORCEPROP 1 LAST VOLTAGE 25V
J 0
(-4900 3450);
DISPLAY 0.617021 (-4900 3450);
PAINT SKYBLUE (-4900 3450);
FORCEPROP 1 LAST MATERIAL X7R
J 0
(-4900 3400);
DISPLAY 0.617021 (-4900 3400);
PAINT SKYBLUE (-4900 3400);
FORCEPROP 1 LASTPIN (-5000 3550) $PN 1
J 0
(-5010 3565);
DISPLAY 0.617021 (-5010 3565);
PAINT ORANGE (-5010 3565);
FORCEPROP 1 LASTPIN (-4800 3550) $PN 2
J 0
(-4815 3565);
DISPLAY 0.617021 (-4815 3565);
PAINT ORANGE (-4815 3565);
FORCEPROP 2 LAST ROOM ST_SATA
J 0
(-4950 3700);
DISPLAY 1.361702 (-4950 3700);
PAINT ORANGE (-4950 3700);
DISPLAY INVISIBLE (-4950 3700);
FORCEPROP 2 LAST CDS_LOCATION C2L13
J 1
(-4900 3650);
DISPLAY 0.617021 (-4900 3650);
PAINT AQUA (-4900 3650);
DISPLAY INVISIBLE (-4900 3650);
FORCEPROP 2 LAST BOM_COST ST_SATA
J 0
(-4950 3650);
DISPLAY 1.361702 (-4950 3650);
PAINT ORANGE (-4950 3650);
DISPLAY INVISIBLE (-4950 3650);
FORCEPROP 2 LAST CDS_LIB dev_discrete
J 0
(-4900 3550);
PAINT ORANGE (-4900 3550);
DISPLAY INVISIBLE (-4900 3550);
FORCEPROP 2 LAST CDS_SEC 1
J 0
(-4900 3700);
PAINT ORANGE (-4900 3700);
DISPLAY INVISIBLE (-4900 3700);
FORCEPROP 2 LAST SEC_TYPE 0402V
J 0
(-4900 3800);
DISPLAY 1.021277 (-4900 3800);
PAINT ORANGE (-4900 3800);
DISPLAY INVISIBLE (-4900 3800);
FORCEPROP 2 LAST SEC 1
J 0
(-4900 3800);
DISPLAY 0.680851 (-4900 3800);
PAINT MONO (-4900 3800);
DISPLAY INVISIBLE (-4900 3800);
FORCEPROP 1 LAST PATH I165
J 0
(-4900 3750);
DISPLAY 0.978723 (-4900 3750);
PAINT WHITE (-4900 3750);
DISPLAY INVISIBLE (-4900 3750);
FORCEADD CAP_A..2
(-4850 4050);
FORCEPROP 1 LAST LOCATION C2L6
J 1
(-4850 4150);
DISPLAY 0.617021 (-4850 4150);
PAINT AQUA (-4850 4150);
FORCEPROP 1 LAST PART_NUMBER A36096-045
J 1
(-4850 4100);
DISPLAY 0.617021 (-4850 4100);
PAINT BLUE (-4850 4100);
FORCEPROP 1 LAST VALUE 0.01UF
J 2
(-4850 3950);
DISPLAY 0.617021 (-4850 3950);
PAINT SKYBLUE (-4850 3950);
FORCEPROP 1 LAST TOLERANCE 10%
J 2
(-4850 3900);
DISPLAY 0.617021 (-4850 3900);
PAINT SKYBLUE (-4850 3900);
FORCEPROP 1 LAST PACK_TYPE 0402V
J 1
(-4850 3850);
DISPLAY 0.617021 (-4850 3850);
PAINT SKYBLUE (-4850 3850);
FORCEPROP 1 LAST VOLTAGE 25V
J 0
(-4850 3950);
DISPLAY 0.617021 (-4850 3950);
PAINT SKYBLUE (-4850 3950);
FORCEPROP 1 LAST MATERIAL X7R
J 0
(-4850 3900);
DISPLAY 0.617021 (-4850 3900);
PAINT SKYBLUE (-4850 3900);
FORCEPROP 1 LASTPIN (-4750 4050) $PN 2
J 0
(-4765 4065);
DISPLAY 0.617021 (-4765 4065);
PAINT ORANGE (-4765 4065);
FORCEPROP 1 LASTPIN (-4950 4050) $PN 1
J 0
(-4960 4065);
DISPLAY 0.617021 (-4960 4065);
PAINT ORANGE (-4960 4065);
FORCEPROP 2 LAST ROOM ST_SATA
J 0
(-4900 4200);
DISPLAY 1.361702 (-4900 4200);
PAINT ORANGE (-4900 4200);
DISPLAY INVISIBLE (-4900 4200);
FORCEPROP 1 LAST PATH I166
J 0
(-4850 4250);
DISPLAY 0.978723 (-4850 4250);
PAINT WHITE (-4850 4250);
DISPLAY INVISIBLE (-4850 4250);
FORCEPROP 2 LAST SEC 1
J 0
(-4850 4300);
DISPLAY 0.680851 (-4850 4300);
PAINT MONO (-4850 4300);
DISPLAY INVISIBLE (-4850 4300);
FORCEPROP 2 LAST SEC_TYPE 0402V
J 0
(-4850 4300);
DISPLAY 1.021277 (-4850 4300);
PAINT ORANGE (-4850 4300);
DISPLAY INVISIBLE (-4850 4300);
FORCEPROP 2 LAST CDS_SEC 1
J 0
(-4850 4200);
PAINT ORANGE (-4850 4200);
DISPLAY INVISIBLE (-4850 4200);
FORCEPROP 2 LAST CDS_LIB dev_discrete
J 0
(-4850 4050);
PAINT ORANGE (-4850 4050);
DISPLAY INVISIBLE (-4850 4050);
FORCEPROP 2 LAST BOM_COST ST_SATA
J 0
(-4900 4150);
DISPLAY 1.361702 (-4900 4150);
PAINT ORANGE (-4900 4150);
DISPLAY INVISIBLE (-4900 4150);
FORCEPROP 2 LAST CDS_LOCATION C2L6
J 1
(-4850 4150);
DISPLAY 0.617021 (-4850 4150);
PAINT AQUA (-4850 4150);
DISPLAY INVISIBLE (-4850 4150);
FORCEADD OFFPAGE..2
(-4300 5300);
FORCEPROP 2 LAST $XR0 116 
J 0
(-4111 5300);
DISPLAY 0.638298 (-4111 5300);
PAINT MONO (-4111 5300);
FORCEPROP 2 LAST CDS_LIB mstr_standard
J 0
(-4300 5300);
PAINT ORANGE (-4300 5300);
DISPLAY INVISIBLE (-4300 5300);
FORCEPROP 2 LAST PATH I170
J 0
(-4100 5350);
DISPLAY 1.021277 (-4100 5350);
PAINT ORANGE (-4100 5350);
DISPLAY INVISIBLE (-4100 5350);
FORCEPROP 1 LAST OFFPAGE TRUE
J 0
(-3975 5175);
DISPLAY 0.872340 (-3975 5175);
PAINT GREEN (-3975 5175);
DISPLAY INVISIBLE (-3975 5175);
FORCEPROP 1 LAST COMMENT_BODY TRUE
J 0
(-4345 5205);
DISPLAY 0.872340 (-4345 5205);
PAINT GREEN (-4345 5205);
DISPLAY INVISIBLE (-4345 5205);
FORCEADD OFFPAGE..2
(-4300 5150);
FORCEPROP 2 LAST $XR0 116 
J 0
(-4111 5150);
DISPLAY 0.638298 (-4111 5150);
PAINT MONO (-4111 5150);
FORCEPROP 2 LAST CDS_LIB mstr_standard
J 0
(-4300 5150);
PAINT ORANGE (-4300 5150);
DISPLAY INVISIBLE (-4300 5150);
FORCEPROP 2 LAST PATH I171
J 0
(-4100 5200);
DISPLAY 1.021277 (-4100 5200);
PAINT ORANGE (-4100 5200);
DISPLAY INVISIBLE (-4100 5200);
FORCEPROP 1 LAST OFFPAGE TRUE
J 0
(-3975 5025);
DISPLAY 0.872340 (-3975 5025);
PAINT GREEN (-3975 5025);
DISPLAY INVISIBLE (-3975 5025);
FORCEPROP 1 LAST COMMENT_BODY TRUE
J 0
(-4345 5055);
DISPLAY 0.872340 (-4345 5055);
PAINT GREEN (-4345 5055);
DISPLAY INVISIBLE (-4345 5055);
FORCEADD CAP_A..2
(-4575 4550);
FORCEPROP 1 LAST LOCATION C2L19
J 1
(-4575 4650);
DISPLAY 0.617021 (-4575 4650);
PAINT AQUA (-4575 4650);
FORCEPROP 1 LAST VALUE 0.01UF
J 2
(-4575 4450);
DISPLAY 0.617021 (-4575 4450);
PAINT SKYBLUE (-4575 4450);
FORCEPROP 1 LAST TOLERANCE 10%
J 2
(-4575 4400);
DISPLAY 0.617021 (-4575 4400);
PAINT SKYBLUE (-4575 4400);
FORCEPROP 1 LAST PACK_TYPE 0402V
J 1
(-4575 4350);
DISPLAY 0.617021 (-4575 4350);
PAINT SKYBLUE (-4575 4350);
FORCEPROP 1 LAST VOLTAGE 25V
J 0
(-4575 4450);
DISPLAY 0.617021 (-4575 4450);
PAINT SKYBLUE (-4575 4450);
FORCEPROP 1 LAST MATERIAL X7R
J 0
(-4575 4400);
DISPLAY 0.617021 (-4575 4400);
PAINT SKYBLUE (-4575 4400);
FORCEPROP 1 LASTPIN (-4475 4550) $PN 2
J 0
(-4490 4565);
DISPLAY 0.617021 (-4490 4565);
PAINT ORANGE (-4490 4565);
FORCEPROP 1 LASTPIN (-4675 4550) $PN 1
J 0
(-4685 4565);
DISPLAY 0.617021 (-4685 4565);
PAINT ORANGE (-4685 4565);
FORCEPROP 1 LAST PART_NUMBER A36096-045
J 1
(-4575 4600);
DISPLAY 0.617021 (-4575 4600);
PAINT BLUE (-4575 4600);
FORCEPROP 2 LAST ROOM ST_SATA
J 0
(-4625 4700);
DISPLAY 1.361702 (-4625 4700);
PAINT ORANGE (-4625 4700);
DISPLAY INVISIBLE (-4625 4700);
FORCEPROP 2 LAST CDS_LOCATION C2L19
J 1
(-4575 4650);
DISPLAY 0.617021 (-4575 4650);
PAINT AQUA (-4575 4650);
DISPLAY INVISIBLE (-4575 4650);
FORCEPROP 2 LAST BOM_COST ST_SATA
J 0
(-4625 4650);
DISPLAY 1.361702 (-4625 4650);
PAINT ORANGE (-4625 4650);
DISPLAY INVISIBLE (-4625 4650);
FORCEPROP 2 LAST CDS_LIB dev_discrete
J 0
(-4575 4550);
PAINT ORANGE (-4575 4550);
DISPLAY INVISIBLE (-4575 4550);
FORCEPROP 2 LAST CDS_SEC 1
J 0
(-4575 4700);
PAINT ORANGE (-4575 4700);
DISPLAY INVISIBLE (-4575 4700);
FORCEPROP 2 LAST SEC_TYPE 0402V
J 0
(-4575 4800);
DISPLAY 1.021277 (-4575 4800);
PAINT ORANGE (-4575 4800);
DISPLAY INVISIBLE (-4575 4800);
FORCEPROP 2 LAST SEC 1
J 0
(-4575 4800);
DISPLAY 0.680851 (-4575 4800);
PAINT MONO (-4575 4800);
DISPLAY INVISIBLE (-4575 4800);
FORCEPROP 1 LAST PATH I172
J 0
(-4575 4750);
DISPLAY 0.978723 (-4575 4750);
PAINT WHITE (-4575 4750);
DISPLAY INVISIBLE (-4575 4750);
FORCEADD CAP_A..2
(-4575 4200);
FORCEPROP 1 LAST PART_NUMBER A36096-045
J 1
(-4575 4250);
DISPLAY 0.617021 (-4575 4250);
PAINT BLUE (-4575 4250);
FORCEPROP 1 LAST VALUE 0.01UF
J 2
(-4575 4100);
DISPLAY 0.617021 (-4575 4100);
PAINT SKYBLUE (-4575 4100);
FORCEPROP 1 LAST TOLERANCE 10%
J 2
(-4575 4050);
DISPLAY 0.617021 (-4575 4050);
PAINT SKYBLUE (-4575 4050);
FORCEPROP 1 LAST PACK_TYPE 0402V
J 1
(-4575 4000);
DISPLAY 0.617021 (-4575 4000);
PAINT SKYBLUE (-4575 4000);
FORCEPROP 1 LAST VOLTAGE 25V
J 0
(-4575 4100);
DISPLAY 0.617021 (-4575 4100);
PAINT SKYBLUE (-4575 4100);
FORCEPROP 1 LAST MATERIAL X7R
J 0
(-4575 4050);
DISPLAY 0.617021 (-4575 4050);
PAINT SKYBLUE (-4575 4050);
FORCEPROP 1 LASTPIN (-4475 4200) $PN 2
J 0
(-4490 4215);
DISPLAY 0.617021 (-4490 4215);
PAINT ORANGE (-4490 4215);
FORCEPROP 1 LASTPIN (-4675 4200) $PN 1
J 0
(-4685 4215);
DISPLAY 0.617021 (-4685 4215);
PAINT ORANGE (-4685 4215);
FORCEPROP 1 LAST LOCATION C2L10
J 1
(-4575 4300);
DISPLAY 0.617021 (-4575 4300);
PAINT AQUA (-4575 4300);
FORCEPROP 2 LAST ROOM ST_SATA
J 0
(-4625 4350);
DISPLAY 1.361702 (-4625 4350);
PAINT ORANGE (-4625 4350);
DISPLAY INVISIBLE (-4625 4350);
FORCEPROP 1 LAST PATH I173
J 0
(-4575 4400);
DISPLAY 0.978723 (-4575 4400);
PAINT WHITE (-4575 4400);
DISPLAY INVISIBLE (-4575 4400);
FORCEPROP 2 LAST SEC 1
J 0
(-4575 4450);
DISPLAY 0.680851 (-4575 4450);
PAINT MONO (-4575 4450);
DISPLAY INVISIBLE (-4575 4450);
FORCEPROP 2 LAST SEC_TYPE 0402V
J 0
(-4575 4450);
DISPLAY 1.021277 (-4575 4450);
PAINT ORANGE (-4575 4450);
DISPLAY INVISIBLE (-4575 4450);
FORCEPROP 2 LAST CDS_SEC 1
J 0
(-4575 4350);
PAINT ORANGE (-4575 4350);
DISPLAY INVISIBLE (-4575 4350);
FORCEPROP 2 LAST CDS_LIB dev_discrete
J 0
(-4575 4200);
PAINT ORANGE (-4575 4200);
DISPLAY INVISIBLE (-4575 4200);
FORCEPROP 2 LAST BOM_COST ST_SATA
J 0
(-4625 4300);
DISPLAY 1.361702 (-4625 4300);
PAINT ORANGE (-4625 4300);
DISPLAY INVISIBLE (-4625 4300);
FORCEPROP 2 LAST CDS_LOCATION C2L10
J 1
(-4575 4300);
DISPLAY 0.617021 (-4575 4300);
PAINT AQUA (-4575 4300);
DISPLAY INVISIBLE (-4575 4300);
FORCEADD CAP_A..2
(-4850 4400);
FORCEPROP 1 LAST PACK_TYPE 0402V
J 1
(-4850 4200);
DISPLAY 0.617021 (-4850 4200);
PAINT SKYBLUE (-4850 4200);
FORCEPROP 1 LAST LOCATION C2L17
J 1
(-4850 4500);
DISPLAY 0.617021 (-4850 4500);
PAINT AQUA (-4850 4500);
FORCEPROP 1 LAST PART_NUMBER A36096-045
J 1
(-4850 4450);
DISPLAY 0.617021 (-4850 4450);
PAINT BLUE (-4850 4450);
FORCEPROP 1 LAST VALUE 0.01UF
J 2
(-4850 4300);
DISPLAY 0.617021 (-4850 4300);
PAINT SKYBLUE (-4850 4300);
FORCEPROP 1 LAST TOLERANCE 10%
J 2
(-4850 4250);
DISPLAY 0.617021 (-4850 4250);
PAINT SKYBLUE (-4850 4250);
FORCEPROP 1 LAST VOLTAGE 25V
J 0
(-4850 4300);
DISPLAY 0.617021 (-4850 4300);
PAINT SKYBLUE (-4850 4300);
FORCEPROP 1 LAST MATERIAL X7R
J 0
(-4850 4250);
DISPLAY 0.617021 (-4850 4250);
PAINT SKYBLUE (-4850 4250);
FORCEPROP 1 LASTPIN (-4950 4400) $PN 1
J 0
(-4960 4415);
DISPLAY 0.617021 (-4960 4415);
PAINT ORANGE (-4960 4415);
FORCEPROP 1 LASTPIN (-4750 4400) $PN 2
J 0
(-4765 4415);
DISPLAY 0.617021 (-4765 4415);
PAINT ORANGE (-4765 4415);
FORCEPROP 2 LAST ROOM ST_SATA
J 0
(-4900 4550);
DISPLAY 1.361702 (-4900 4550);
PAINT ORANGE (-4900 4550);
DISPLAY INVISIBLE (-4900 4550);
FORCEPROP 2 LAST CDS_LOCATION C2L17
J 1
(-4850 4500);
DISPLAY 0.617021 (-4850 4500);
PAINT AQUA (-4850 4500);
DISPLAY INVISIBLE (-4850 4500);
FORCEPROP 2 LAST BOM_COST ST_SATA
J 0
(-4900 4500);
DISPLAY 1.361702 (-4900 4500);
PAINT ORANGE (-4900 4500);
DISPLAY INVISIBLE (-4900 4500);
FORCEPROP 2 LAST CDS_LIB dev_discrete
J 0
(-4850 4400);
PAINT ORANGE (-4850 4400);
DISPLAY INVISIBLE (-4850 4400);
FORCEPROP 2 LAST CDS_SEC 1
J 0
(-4850 4550);
PAINT ORANGE (-4850 4550);
DISPLAY INVISIBLE (-4850 4550);
FORCEPROP 2 LAST SEC_TYPE 0402V
J 0
(-4850 4650);
DISPLAY 1.021277 (-4850 4650);
PAINT ORANGE (-4850 4650);
DISPLAY INVISIBLE (-4850 4650);
FORCEPROP 2 LAST SEC 1
J 0
(-4850 4650);
DISPLAY 0.680851 (-4850 4650);
PAINT MONO (-4850 4650);
DISPLAY INVISIBLE (-4850 4650);
FORCEPROP 1 LAST PATH I174
J 0
(-4850 4600);
DISPLAY 0.978723 (-4850 4600);
PAINT WHITE (-4850 4600);
DISPLAY INVISIBLE (-4850 4600);
FORCEADD TAP..6
(-5250 4400);
FORCEPROP 3 LASTPIN (-5200 4400) SIG_NAME SATA6G_PCH_PCIE_UP_SATA_RXN<0>
J 0
(-5190 4410);
DISPLAY 0.659574 (-5190 4410);
PAINT MONO (-5190 4410);
DISPLAY INVISIBLE (-5190 4410);
FORCEPROP 1 LASTPIN (-5200 4400) BN 0
J 0
(-5252 4408);
DISPLAY 0.617021 (-5252 4408);
PAINT GREEN (-5252 4408);
FORCEPROP 2 LAST CDS_LIB mstr_standard
J 0
(-5250 4400);
PAINT ORANGE (-5250 4400);
DISPLAY INVISIBLE (-5250 4400);
FORCEPROP 1 LAST PATH I175
J 0
(-5252 4400);
DISPLAY 0.872340 (-5252 4400);
PAINT GREEN (-5252 4400);
DISPLAY INVISIBLE (-5252 4400);
FORCEPROP 1 LAST BODY_TYPE PLUMBING
J 0
(-5250 4350);
DISPLAY 0.872340 (-5250 4350);
PAINT GREEN (-5250 4350);
DISPLAY INVISIBLE (-5250 4350);
FORCEPROP 1 LAST HDL_TAP TRUE
J 0
(-4925 4275);
DISPLAY 0.872340 (-4925 4275);
PAINT ORANGE (-4925 4275);
DISPLAY INVISIBLE (-4925 4275);
FORCEADD TAP..6
(-5400 4550);
FORCEPROP 3 LASTPIN (-5350 4550) SIG_NAME SATA6G_PCH_PCIE_UP_SATA_RXP<0>
J 0
(-5340 4560);
DISPLAY 0.659574 (-5340 4560);
PAINT MONO (-5340 4560);
DISPLAY INVISIBLE (-5340 4560);
FORCEPROP 1 LASTPIN (-5350 4550) BN 0
J 0
(-5402 4558);
DISPLAY 0.617021 (-5402 4558);
PAINT GREEN (-5402 4558);
FORCEPROP 2 LAST CDS_LIB mstr_standard
J 0
(-5400 4550);
PAINT ORANGE (-5400 4550);
DISPLAY INVISIBLE (-5400 4550);
FORCEPROP 1 LAST PATH I176
J 0
(-5402 4550);
DISPLAY 0.872340 (-5402 4550);
PAINT GREEN (-5402 4550);
DISPLAY INVISIBLE (-5402 4550);
FORCEPROP 1 LAST BODY_TYPE PLUMBING
J 0
(-5400 4500);
DISPLAY 0.872340 (-5400 4500);
PAINT GREEN (-5400 4500);
DISPLAY INVISIBLE (-5400 4500);
FORCEPROP 1 LAST HDL_TAP TRUE
J 0
(-5075 4425);
DISPLAY 0.872340 (-5075 4425);
PAINT ORANGE (-5075 4425);
DISPLAY INVISIBLE (-5075 4425);
FORCEADD TAP..6
(-5400 4200);
FORCEPROP 3 LASTPIN (-5350 4200) SIG_NAME SATA6G_PCH_PCIE_UP_SATA_RXP<1>
J 0
(-5340 4210);
DISPLAY 0.659574 (-5340 4210);
PAINT MONO (-5340 4210);
DISPLAY INVISIBLE (-5340 4210);
FORCEPROP 1 LASTPIN (-5350 4200) BN 1
J 0
(-5402 4208);
DISPLAY 0.617021 (-5402 4208);
PAINT GREEN (-5402 4208);
FORCEPROP 1 LAST PATH I177
J 0
(-5402 4200);
DISPLAY 0.872340 (-5402 4200);
PAINT GREEN (-5402 4200);
DISPLAY INVISIBLE (-5402 4200);
FORCEPROP 2 LAST CDS_LIB mstr_standard
J 0
(-5400 4200);
PAINT ORANGE (-5400 4200);
DISPLAY INVISIBLE (-5400 4200);
FORCEPROP 1 LAST BODY_TYPE PLUMBING
J 0
(-5400 4150);
DISPLAY 0.872340 (-5400 4150);
PAINT GREEN (-5400 4150);
DISPLAY INVISIBLE (-5400 4150);
FORCEPROP 1 LAST HDL_TAP TRUE
J 0
(-5075 4075);
DISPLAY 0.872340 (-5075 4075);
PAINT ORANGE (-5075 4075);
DISPLAY INVISIBLE (-5075 4075);
FORCEADD CAP_A..2
(-4575 3700);
FORCEPROP 1 LAST LOCATION C2L15
J 1
(-4575 3800);
DISPLAY 0.617021 (-4575 3800);
PAINT AQUA (-4575 3800);
FORCEPROP 1 LAST PART_NUMBER A36096-045
J 1
(-4575 3750);
DISPLAY 0.617021 (-4575 3750);
PAINT BLUE (-4575 3750);
FORCEPROP 1 LAST VALUE 0.01UF
J 2
(-4575 3600);
DISPLAY 0.617021 (-4575 3600);
PAINT SKYBLUE (-4575 3600);
FORCEPROP 1 LAST TOLERANCE 10%
J 2
(-4575 3550);
DISPLAY 0.617021 (-4575 3550);
PAINT SKYBLUE (-4575 3550);
FORCEPROP 1 LAST VOLTAGE 25V
J 0
(-4575 3600);
DISPLAY 0.617021 (-4575 3600);
PAINT SKYBLUE (-4575 3600);
FORCEPROP 1 LAST MATERIAL X7R
J 0
(-4575 3550);
DISPLAY 0.617021 (-4575 3550);
PAINT SKYBLUE (-4575 3550);
FORCEPROP 1 LASTPIN (-4475 3700) $PN 2
J 0
(-4490 3715);
DISPLAY 0.617021 (-4490 3715);
PAINT ORANGE (-4490 3715);
FORCEPROP 1 LASTPIN (-4675 3700) $PN 1
J 0
(-4685 3715);
DISPLAY 0.617021 (-4685 3715);
PAINT ORANGE (-4685 3715);
FORCEPROP 1 LAST PACK_TYPE 0402V
J 1
(-4575 3500);
DISPLAY 0.617021 (-4575 3500);
PAINT SKYBLUE (-4575 3500);
FORCEPROP 2 LAST ROOM ST_SATA
J 0
(-4625 3850);
DISPLAY 1.361702 (-4625 3850);
PAINT ORANGE (-4625 3850);
DISPLAY INVISIBLE (-4625 3850);
FORCEPROP 2 LAST CDS_LOCATION C2L15
J 1
(-4575 3800);
DISPLAY 0.617021 (-4575 3800);
PAINT AQUA (-4575 3800);
DISPLAY INVISIBLE (-4575 3800);
FORCEPROP 2 LAST BOM_COST ST_SATA
J 0
(-4625 3800);
DISPLAY 1.361702 (-4625 3800);
PAINT ORANGE (-4625 3800);
DISPLAY INVISIBLE (-4625 3800);
FORCEPROP 2 LAST CDS_LIB dev_discrete
J 0
(-4575 3700);
PAINT ORANGE (-4575 3700);
DISPLAY INVISIBLE (-4575 3700);
FORCEPROP 2 LAST CDS_SEC 1
J 0
(-4575 3850);
PAINT ORANGE (-4575 3850);
DISPLAY INVISIBLE (-4575 3850);
FORCEPROP 2 LAST SEC_TYPE 0402V
J 0
(-4575 3950);
DISPLAY 1.021277 (-4575 3950);
PAINT ORANGE (-4575 3950);
DISPLAY INVISIBLE (-4575 3950);
FORCEPROP 2 LAST SEC 1
J 0
(-4575 3950);
DISPLAY 0.680851 (-4575 3950);
PAINT MONO (-4575 3950);
DISPLAY INVISIBLE (-4575 3950);
FORCEPROP 1 LAST PATH I191
J 0
(-4575 3900);
DISPLAY 0.978723 (-4575 3900);
PAINT WHITE (-4575 3900);
DISPLAY INVISIBLE (-4575 3900);
FORCEADD CAP_A..2
(-4575 3350);
FORCEPROP 1 LAST LOCATION C2L4
J 1
(-4575 3450);
DISPLAY 0.617021 (-4575 3450);
PAINT AQUA (-4575 3450);
FORCEPROP 1 LAST PART_NUMBER A36096-045
J 1
(-4575 3400);
DISPLAY 0.617021 (-4575 3400);
PAINT BLUE (-4575 3400);
FORCEPROP 1 LAST TOLERANCE 10%
J 2
(-4575 3200);
DISPLAY 0.617021 (-4575 3200);
PAINT SKYBLUE (-4575 3200);
FORCEPROP 1 LAST PACK_TYPE 0402V
J 1
(-4575 3150);
DISPLAY 0.617021 (-4575 3150);
PAINT SKYBLUE (-4575 3150);
FORCEPROP 1 LAST VOLTAGE 25V
J 0
(-4575 3250);
DISPLAY 0.617021 (-4575 3250);
PAINT SKYBLUE (-4575 3250);
FORCEPROP 1 LAST MATERIAL X7R
J 0
(-4575 3200);
DISPLAY 0.617021 (-4575 3200);
PAINT SKYBLUE (-4575 3200);
FORCEPROP 1 LASTPIN (-4475 3350) $PN 2
J 0
(-4490 3365);
DISPLAY 0.617021 (-4490 3365);
PAINT ORANGE (-4490 3365);
FORCEPROP 1 LASTPIN (-4675 3350) $PN 1
J 0
(-4685 3365);
DISPLAY 0.617021 (-4685 3365);
PAINT ORANGE (-4685 3365);
FORCEPROP 1 LAST VALUE 0.01UF
J 2
(-4575 3250);
DISPLAY 0.617021 (-4575 3250);
PAINT SKYBLUE (-4575 3250);
FORCEPROP 2 LAST ROOM ST_SATA
J 0
(-4625 3500);
DISPLAY 1.361702 (-4625 3500);
PAINT ORANGE (-4625 3500);
DISPLAY INVISIBLE (-4625 3500);
FORCEPROP 1 LAST PATH I192
J 0
(-4575 3550);
DISPLAY 0.978723 (-4575 3550);
PAINT WHITE (-4575 3550);
DISPLAY INVISIBLE (-4575 3550);
FORCEPROP 2 LAST SEC 1
J 0
(-4575 3600);
DISPLAY 0.680851 (-4575 3600);
PAINT MONO (-4575 3600);
DISPLAY INVISIBLE (-4575 3600);
FORCEPROP 2 LAST SEC_TYPE 0402V
J 0
(-4575 3600);
DISPLAY 1.021277 (-4575 3600);
PAINT ORANGE (-4575 3600);
DISPLAY INVISIBLE (-4575 3600);
FORCEPROP 2 LAST CDS_SEC 1
J 0
(-4575 3500);
PAINT ORANGE (-4575 3500);
DISPLAY INVISIBLE (-4575 3500);
FORCEPROP 2 LAST CDS_LIB dev_discrete
J 0
(-4575 3350);
PAINT ORANGE (-4575 3350);
DISPLAY INVISIBLE (-4575 3350);
FORCEPROP 2 LAST BOM_COST ST_SATA
J 0
(-4625 3450);
DISPLAY 1.361702 (-4625 3450);
PAINT ORANGE (-4625 3450);
DISPLAY INVISIBLE (-4625 3450);
FORCEPROP 2 LAST CDS_LOCATION C2L4
J 1
(-4575 3450);
DISPLAY 0.617021 (-4575 3450);
PAINT AQUA (-4575 3450);
DISPLAY INVISIBLE (-4575 3450);
FORCEADD CAP_A..2
(-4900 3200);
FORCEPROP 1 LAST LOCATION C2L3
J 1
(-4900 3300);
DISPLAY 0.617021 (-4900 3300);
PAINT AQUA (-4900 3300);
FORCEPROP 1 LAST VALUE 0.01UF
J 2
(-4900 3100);
DISPLAY 0.617021 (-4900 3100);
PAINT SKYBLUE (-4900 3100);
FORCEPROP 1 LAST TOLERANCE 10%
J 2
(-4900 3050);
DISPLAY 0.617021 (-4900 3050);
PAINT SKYBLUE (-4900 3050);
FORCEPROP 1 LAST PACK_TYPE 0402V
J 1
(-4900 3000);
DISPLAY 0.617021 (-4900 3000);
PAINT SKYBLUE (-4900 3000);
FORCEPROP 1 LAST VOLTAGE 25V
J 0
(-4900 3100);
DISPLAY 0.617021 (-4900 3100);
PAINT SKYBLUE (-4900 3100);
FORCEPROP 1 LAST MATERIAL X7R
J 0
(-4900 3050);
DISPLAY 0.617021 (-4900 3050);
PAINT SKYBLUE (-4900 3050);
FORCEPROP 1 LASTPIN (-5000 3200) $PN 1
J 0
(-5010 3215);
DISPLAY 0.617021 (-5010 3215);
PAINT ORANGE (-5010 3215);
FORCEPROP 1 LASTPIN (-4800 3200) $PN 2
J 0
(-4815 3215);
DISPLAY 0.617021 (-4815 3215);
PAINT ORANGE (-4815 3215);
FORCEPROP 1 LAST PART_NUMBER A36096-045
J 1
(-4900 3250);
DISPLAY 0.617021 (-4900 3250);
PAINT BLUE (-4900 3250);
FORCEPROP 2 LAST ROOM ST_SATA
J 0
(-4950 3350);
DISPLAY 1.361702 (-4950 3350);
PAINT ORANGE (-4950 3350);
DISPLAY INVISIBLE (-4950 3350);
FORCEPROP 2 LAST CDS_LOCATION C2L3
J 1
(-4900 3300);
DISPLAY 0.617021 (-4900 3300);
PAINT AQUA (-4900 3300);
DISPLAY INVISIBLE (-4900 3300);
FORCEPROP 2 LAST BOM_COST ST_SATA
J 0
(-4950 3300);
DISPLAY 1.361702 (-4950 3300);
PAINT ORANGE (-4950 3300);
DISPLAY INVISIBLE (-4950 3300);
FORCEPROP 2 LAST CDS_LIB dev_discrete
J 0
(-4900 3200);
PAINT ORANGE (-4900 3200);
DISPLAY INVISIBLE (-4900 3200);
FORCEPROP 2 LAST CDS_SEC 1
J 0
(-4900 3350);
PAINT ORANGE (-4900 3350);
DISPLAY INVISIBLE (-4900 3350);
FORCEPROP 2 LAST SEC_TYPE 0402V
J 0
(-4900 3450);
DISPLAY 1.021277 (-4900 3450);
PAINT ORANGE (-4900 3450);
DISPLAY INVISIBLE (-4900 3450);
FORCEPROP 2 LAST SEC 1
J 0
(-4900 3450);
DISPLAY 0.680851 (-4900 3450);
PAINT MONO (-4900 3450);
DISPLAY INVISIBLE (-4900 3450);
FORCEPROP 1 LAST PATH I194
J 0
(-4900 3400);
DISPLAY 0.978723 (-4900 3400);
PAINT WHITE (-4900 3400);
DISPLAY INVISIBLE (-4900 3400);
FORCEADD CAP_A..2
(-4600 2900);
FORCEPROP 1 LAST LOCATION C2L20
J 1
(-4600 3000);
DISPLAY 0.617021 (-4600 3000);
PAINT AQUA (-4600 3000);
FORCEPROP 1 LAST PART_NUMBER A36096-045
J 1
(-4600 2950);
DISPLAY 0.617021 (-4600 2950);
PAINT BLUE (-4600 2950);
FORCEPROP 1 LAST VALUE 0.01UF
J 2
(-4600 2800);
DISPLAY 0.617021 (-4600 2800);
PAINT SKYBLUE (-4600 2800);
FORCEPROP 1 LAST TOLERANCE 10%
J 2
(-4600 2750);
DISPLAY 0.617021 (-4600 2750);
PAINT SKYBLUE (-4600 2750);
FORCEPROP 1 LAST PACK_TYPE 0402V
J 1
(-4600 2700);
DISPLAY 0.617021 (-4600 2700);
PAINT SKYBLUE (-4600 2700);
FORCEPROP 1 LAST VOLTAGE 25V
J 0
(-4600 2800);
DISPLAY 0.617021 (-4600 2800);
PAINT SKYBLUE (-4600 2800);
FORCEPROP 1 LAST MATERIAL X7R
J 0
(-4600 2750);
DISPLAY 0.617021 (-4600 2750);
PAINT SKYBLUE (-4600 2750);
FORCEPROP 1 LASTPIN (-4700 2900) $PN 1
J 0
(-4710 2915);
DISPLAY 0.617021 (-4710 2915);
PAINT ORANGE (-4710 2915);
FORCEPROP 1 LASTPIN (-4500 2900) $PN 2
J 0
(-4515 2915);
DISPLAY 0.617021 (-4515 2915);
PAINT ORANGE (-4515 2915);
FORCEPROP 2 LAST ROOM ST_SATA
J 0
(-4650 3050);
DISPLAY 1.361702 (-4650 3050);
PAINT ORANGE (-4650 3050);
DISPLAY INVISIBLE (-4650 3050);
FORCEPROP 2 LAST CDS_LOCATION C2L20
J 1
(-4600 3000);
DISPLAY 0.617021 (-4600 3000);
PAINT AQUA (-4600 3000);
DISPLAY INVISIBLE (-4600 3000);
FORCEPROP 2 LAST BOM_COST ST_SATA
J 0
(-4650 3000);
DISPLAY 1.361702 (-4650 3000);
PAINT ORANGE (-4650 3000);
DISPLAY INVISIBLE (-4650 3000);
FORCEPROP 2 LAST CDS_LIB dev_discrete
J 0
(-4600 2900);
PAINT ORANGE (-4600 2900);
DISPLAY INVISIBLE (-4600 2900);
FORCEPROP 2 LAST CDS_SEC 1
J 0
(-4600 3050);
PAINT ORANGE (-4600 3050);
DISPLAY INVISIBLE (-4600 3050);
FORCEPROP 2 LAST SEC_TYPE 0402V
J 0
(-4600 3150);
DISPLAY 1.021277 (-4600 3150);
PAINT ORANGE (-4600 3150);
DISPLAY INVISIBLE (-4600 3150);
FORCEPROP 2 LAST SEC 1
J 0
(-4600 3150);
DISPLAY 0.680851 (-4600 3150);
PAINT MONO (-4600 3150);
DISPLAY INVISIBLE (-4600 3150);
FORCEPROP 1 LAST PATH I195
J 0
(-4600 3100);
DISPLAY 0.978723 (-4600 3100);
PAINT WHITE (-4600 3100);
DISPLAY INVISIBLE (-4600 3100);
FORCEADD CAP_A..2
(-4575 2550);
FORCEPROP 1 LAST TOLERANCE 10%
J 2
(-4575 2400);
DISPLAY 0.617021 (-4575 2400);
PAINT SKYBLUE (-4575 2400);
FORCEPROP 1 LAST PACK_TYPE 0402V
J 1
(-4575 2350);
DISPLAY 0.617021 (-4575 2350);
PAINT SKYBLUE (-4575 2350);
FORCEPROP 1 LAST VOLTAGE 25V
J 0
(-4575 2450);
DISPLAY 0.617021 (-4575 2450);
PAINT SKYBLUE (-4575 2450);
FORCEPROP 1 LAST MATERIAL X7R
J 0
(-4575 2400);
DISPLAY 0.617021 (-4575 2400);
PAINT SKYBLUE (-4575 2400);
FORCEPROP 1 LASTPIN (-4475 2550) $PN 2
J 0
(-4490 2565);
DISPLAY 0.617021 (-4490 2565);
PAINT ORANGE (-4490 2565);
FORCEPROP 1 LASTPIN (-4675 2550) $PN 1
J 0
(-4685 2565);
DISPLAY 0.617021 (-4685 2565);
PAINT ORANGE (-4685 2565);
FORCEPROP 1 LAST VALUE 0.01UF
J 2
(-4575 2450);
DISPLAY 0.617021 (-4575 2450);
PAINT SKYBLUE (-4575 2450);
FORCEPROP 1 LAST PART_NUMBER A36096-045
J 1
(-4575 2600);
DISPLAY 0.617021 (-4575 2600);
PAINT BLUE (-4575 2600);
FORCEPROP 1 LAST LOCATION C2L12
J 1
(-4575 2650);
DISPLAY 0.617021 (-4575 2650);
PAINT AQUA (-4575 2650);
FORCEPROP 2 LAST ROOM ST_SATA
J 0
(-4625 2700);
DISPLAY 1.361702 (-4625 2700);
PAINT ORANGE (-4625 2700);
DISPLAY INVISIBLE (-4625 2700);
FORCEPROP 1 LAST PATH I196
J 0
(-4575 2750);
DISPLAY 0.978723 (-4575 2750);
PAINT WHITE (-4575 2750);
DISPLAY INVISIBLE (-4575 2750);
FORCEPROP 2 LAST SEC 1
J 0
(-4575 2800);
DISPLAY 0.680851 (-4575 2800);
PAINT MONO (-4575 2800);
DISPLAY INVISIBLE (-4575 2800);
FORCEPROP 2 LAST SEC_TYPE 0402V
J 0
(-4575 2800);
DISPLAY 1.021277 (-4575 2800);
PAINT ORANGE (-4575 2800);
DISPLAY INVISIBLE (-4575 2800);
FORCEPROP 2 LAST CDS_SEC 1
J 0
(-4575 2700);
PAINT ORANGE (-4575 2700);
DISPLAY INVISIBLE (-4575 2700);
FORCEPROP 2 LAST CDS_LIB dev_discrete
J 0
(-4575 2550);
PAINT ORANGE (-4575 2550);
DISPLAY INVISIBLE (-4575 2550);
FORCEPROP 2 LAST BOM_COST ST_SATA
J 0
(-4625 2650);
DISPLAY 1.361702 (-4625 2650);
PAINT ORANGE (-4625 2650);
DISPLAY INVISIBLE (-4625 2650);
FORCEPROP 2 LAST CDS_LOCATION C2L12
J 1
(-4575 2650);
DISPLAY 0.617021 (-4575 2650);
PAINT AQUA (-4575 2650);
DISPLAY INVISIBLE (-4575 2650);
FORCEADD CAP_A..2
(-4950 2750);
FORCEPROP 1 LAST VALUE 0.01UF
J 2
(-4950 2650);
DISPLAY 0.617021 (-4950 2650);
PAINT SKYBLUE (-4950 2650);
FORCEPROP 1 LAST TOLERANCE 10%
J 2
(-4950 2600);
DISPLAY 0.617021 (-4950 2600);
PAINT SKYBLUE (-4950 2600);
FORCEPROP 1 LAST PACK_TYPE 0402V
J 1
(-4950 2550);
DISPLAY 0.617021 (-4950 2550);
PAINT SKYBLUE (-4950 2550);
FORCEPROP 1 LAST VOLTAGE 25V
J 0
(-4950 2650);
DISPLAY 0.617021 (-4950 2650);
PAINT SKYBLUE (-4950 2650);
FORCEPROP 1 LAST MATERIAL X7R
J 0
(-4950 2600);
DISPLAY 0.617021 (-4950 2600);
PAINT SKYBLUE (-4950 2600);
FORCEPROP 1 LASTPIN (-5050 2750) $PN 1
J 0
(-5060 2765);
DISPLAY 0.617021 (-5060 2765);
PAINT ORANGE (-5060 2765);
FORCEPROP 1 LASTPIN (-4850 2750) $PN 2
J 0
(-4865 2765);
DISPLAY 0.617021 (-4865 2765);
PAINT ORANGE (-4865 2765);
FORCEPROP 1 LAST PART_NUMBER A36096-045
J 1
(-4950 2800);
DISPLAY 0.617021 (-4950 2800);
PAINT BLUE (-4950 2800);
FORCEPROP 1 LAST LOCATION C2L18
J 1
(-4950 2850);
DISPLAY 0.617021 (-4950 2850);
PAINT AQUA (-4950 2850);
FORCEPROP 2 LAST ROOM ST_SATA
J 0
(-5000 2900);
DISPLAY 1.361702 (-5000 2900);
PAINT ORANGE (-5000 2900);
DISPLAY INVISIBLE (-5000 2900);
FORCEPROP 2 LAST CDS_LOCATION C2L18
J 1
(-4950 2850);
DISPLAY 0.617021 (-4950 2850);
PAINT AQUA (-4950 2850);
DISPLAY INVISIBLE (-4950 2850);
FORCEPROP 2 LAST BOM_COST ST_SATA
J 0
(-5000 2850);
DISPLAY 1.361702 (-5000 2850);
PAINT ORANGE (-5000 2850);
DISPLAY INVISIBLE (-5000 2850);
FORCEPROP 2 LAST CDS_LIB dev_discrete
J 0
(-4950 2750);
PAINT ORANGE (-4950 2750);
DISPLAY INVISIBLE (-4950 2750);
FORCEPROP 2 LAST CDS_SEC 1
J 0
(-4950 2900);
PAINT ORANGE (-4950 2900);
DISPLAY INVISIBLE (-4950 2900);
FORCEPROP 2 LAST SEC_TYPE 0402V
J 0
(-4950 3000);
DISPLAY 1.021277 (-4950 3000);
PAINT ORANGE (-4950 3000);
DISPLAY INVISIBLE (-4950 3000);
FORCEPROP 2 LAST SEC 1
J 0
(-4950 3000);
DISPLAY 0.680851 (-4950 3000);
PAINT MONO (-4950 3000);
DISPLAY INVISIBLE (-4950 3000);
FORCEPROP 1 LAST PATH I197
J 0
(-4950 2950);
DISPLAY 0.978723 (-4950 2950);
PAINT WHITE (-4950 2950);
DISPLAY INVISIBLE (-4950 2950);
FORCEADD TAP..6
(-5250 3550);
FORCEPROP 3 LASTPIN (-5200 3550) SIG_NAME SATA6G_PCH_PCIE_UP_SATA_RXN<2>
J 0
(-5190 3560);
DISPLAY 0.659574 (-5190 3560);
PAINT MONO (-5190 3560);
DISPLAY INVISIBLE (-5190 3560);
FORCEPROP 1 LASTPIN (-5200 3550) BN 2
J 0
(-5252 3558);
DISPLAY 0.617021 (-5252 3558);
PAINT GREEN (-5252 3558);
FORCEPROP 2 LAST CDS_LIB mstr_standard
J 0
(-5250 3550);
PAINT ORANGE (-5250 3550);
DISPLAY INVISIBLE (-5250 3550);
FORCEPROP 1 LAST PATH I198
J 0
(-5252 3550);
DISPLAY 0.872340 (-5252 3550);
PAINT GREEN (-5252 3550);
DISPLAY INVISIBLE (-5252 3550);
FORCEPROP 1 LAST BODY_TYPE PLUMBING
J 0
(-5250 3500);
DISPLAY 0.872340 (-5250 3500);
PAINT GREEN (-5250 3500);
DISPLAY INVISIBLE (-5250 3500);
FORCEPROP 1 LAST HDL_TAP TRUE
J 0
(-4925 3425);
DISPLAY 0.872340 (-4925 3425);
PAINT ORANGE (-4925 3425);
DISPLAY INVISIBLE (-4925 3425);
FORCEADD TAP..6
(-5400 3700);
FORCEPROP 3 LASTPIN (-5350 3700) SIG_NAME SATA6G_PCH_PCIE_UP_SATA_RXP<2>
J 0
(-5340 3710);
DISPLAY 0.659574 (-5340 3710);
PAINT MONO (-5340 3710);
DISPLAY INVISIBLE (-5340 3710);
FORCEPROP 1 LASTPIN (-5350 3700) BN 2
J 0
(-5402 3708);
DISPLAY 0.617021 (-5402 3708);
PAINT GREEN (-5402 3708);
FORCEPROP 2 LAST CDS_LIB mstr_standard
J 0
(-5400 3700);
PAINT ORANGE (-5400 3700);
DISPLAY INVISIBLE (-5400 3700);
FORCEPROP 1 LAST PATH I199
J 0
(-5402 3700);
DISPLAY 0.872340 (-5402 3700);
PAINT GREEN (-5402 3700);
DISPLAY INVISIBLE (-5402 3700);
FORCEPROP 1 LAST BODY_TYPE PLUMBING
J 0
(-5400 3650);
DISPLAY 0.872340 (-5400 3650);
PAINT GREEN (-5400 3650);
DISPLAY INVISIBLE (-5400 3650);
FORCEPROP 1 LAST HDL_TAP TRUE
J 0
(-5075 3575);
DISPLAY 0.872340 (-5075 3575);
PAINT ORANGE (-5075 3575);
DISPLAY INVISIBLE (-5075 3575);
FORCEADD TAP..6
(-5400 3350);
FORCEPROP 3 LASTPIN (-5350 3350) SIG_NAME SATA6G_PCH_PCIE_UP_SATA_RXP<3>
J 0
(-5340 3360);
DISPLAY 0.659574 (-5340 3360);
PAINT MONO (-5340 3360);
DISPLAY INVISIBLE (-5340 3360);
FORCEPROP 1 LASTPIN (-5350 3350) BN 3
J 0
(-5402 3358);
DISPLAY 0.617021 (-5402 3358);
PAINT GREEN (-5402 3358);
FORCEPROP 1 LAST PATH I200
J 0
(-5402 3350);
DISPLAY 0.872340 (-5402 3350);
PAINT GREEN (-5402 3350);
DISPLAY INVISIBLE (-5402 3350);
FORCEPROP 2 LAST CDS_LIB mstr_standard
J 0
(-5400 3350);
PAINT ORANGE (-5400 3350);
DISPLAY INVISIBLE (-5400 3350);
FORCEPROP 1 LAST BODY_TYPE PLUMBING
J 0
(-5400 3300);
DISPLAY 0.872340 (-5400 3300);
PAINT GREEN (-5400 3300);
DISPLAY INVISIBLE (-5400 3300);
FORCEPROP 1 LAST HDL_TAP TRUE
J 0
(-5075 3225);
DISPLAY 0.872340 (-5075 3225);
PAINT ORANGE (-5075 3225);
DISPLAY INVISIBLE (-5075 3225);
FORCEADD TAP..6
(-5250 3200);
FORCEPROP 3 LASTPIN (-5200 3200) SIG_NAME SATA6G_PCH_PCIE_UP_SATA_RXN<3>
J 0
(-5190 3210);
DISPLAY 0.659574 (-5190 3210);
PAINT MONO (-5190 3210);
DISPLAY INVISIBLE (-5190 3210);
FORCEPROP 1 LASTPIN (-5200 3200) BN 3
J 0
(-5252 3208);
DISPLAY 0.617021 (-5252 3208);
PAINT GREEN (-5252 3208);
FORCEPROP 1 LAST PATH I201
J 0
(-5252 3200);
DISPLAY 0.872340 (-5252 3200);
PAINT GREEN (-5252 3200);
DISPLAY INVISIBLE (-5252 3200);
FORCEPROP 2 LAST CDS_LIB mstr_standard
J 0
(-5250 3200);
PAINT ORANGE (-5250 3200);
DISPLAY INVISIBLE (-5250 3200);
FORCEPROP 1 LAST BODY_TYPE PLUMBING
J 0
(-5250 3150);
DISPLAY 0.872340 (-5250 3150);
PAINT GREEN (-5250 3150);
DISPLAY INVISIBLE (-5250 3150);
FORCEPROP 1 LAST HDL_TAP TRUE
J 0
(-4925 3075);
DISPLAY 0.872340 (-4925 3075);
PAINT ORANGE (-4925 3075);
DISPLAY INVISIBLE (-4925 3075);
FORCEADD TAP..6
(-5400 2900);
FORCEPROP 3 LASTPIN (-5350 2900) SIG_NAME SATA6G_PCH_PCIE_UP_SATA_RXP<4>
J 0
(-5340 2910);
DISPLAY 0.659574 (-5340 2910);
PAINT MONO (-5340 2910);
DISPLAY INVISIBLE (-5340 2910);
FORCEPROP 1 LASTPIN (-5350 2900) BN 4
J 0
(-5402 2908);
DISPLAY 0.617021 (-5402 2908);
PAINT GREEN (-5402 2908);
FORCEPROP 2 LAST CDS_LIB mstr_standard
J 0
(-5400 2900);
PAINT ORANGE (-5400 2900);
DISPLAY INVISIBLE (-5400 2900);
FORCEPROP 1 LAST PATH I202
J 0
(-5402 2900);
DISPLAY 0.872340 (-5402 2900);
PAINT GREEN (-5402 2900);
DISPLAY INVISIBLE (-5402 2900);
FORCEPROP 1 LAST BODY_TYPE PLUMBING
J 0
(-5400 2850);
DISPLAY 0.872340 (-5400 2850);
PAINT GREEN (-5400 2850);
DISPLAY INVISIBLE (-5400 2850);
FORCEPROP 1 LAST HDL_TAP TRUE
J 0
(-5075 2775);
DISPLAY 0.872340 (-5075 2775);
PAINT ORANGE (-5075 2775);
DISPLAY INVISIBLE (-5075 2775);
FORCEADD TAP..6
(-5400 2550);
FORCEPROP 3 LASTPIN (-5350 2550) SIG_NAME SATA6G_PCH_PCIE_UP_SATA_RXP<5>
J 0
(-5340 2560);
DISPLAY 0.659574 (-5340 2560);
PAINT MONO (-5340 2560);
DISPLAY INVISIBLE (-5340 2560);
FORCEPROP 1 LASTPIN (-5350 2550) BN 5
J 0
(-5402 2558);
DISPLAY 0.617021 (-5402 2558);
PAINT GREEN (-5402 2558);
FORCEPROP 1 LAST PATH I203
J 0
(-5402 2550);
DISPLAY 0.872340 (-5402 2550);
PAINT GREEN (-5402 2550);
DISPLAY INVISIBLE (-5402 2550);
FORCEPROP 2 LAST CDS_LIB mstr_standard
J 0
(-5400 2550);
PAINT ORANGE (-5400 2550);
DISPLAY INVISIBLE (-5400 2550);
FORCEPROP 1 LAST BODY_TYPE PLUMBING
J 0
(-5400 2500);
DISPLAY 0.872340 (-5400 2500);
PAINT GREEN (-5400 2500);
DISPLAY INVISIBLE (-5400 2500);
FORCEPROP 1 LAST HDL_TAP TRUE
J 0
(-5075 2425);
DISPLAY 0.872340 (-5075 2425);
PAINT ORANGE (-5075 2425);
DISPLAY INVISIBLE (-5075 2425);
FORCEADD TAP..6
(-5250 2750);
FORCEPROP 3 LASTPIN (-5200 2750) SIG_NAME SATA6G_PCH_PCIE_UP_SATA_RXN<4>
J 0
(-5190 2760);
DISPLAY 0.659574 (-5190 2760);
PAINT MONO (-5190 2760);
DISPLAY INVISIBLE (-5190 2760);
FORCEPROP 1 LASTPIN (-5200 2750) BN 4
J 0
(-5252 2758);
DISPLAY 0.617021 (-5252 2758);
PAINT GREEN (-5252 2758);
FORCEPROP 2 LAST CDS_LIB mstr_standard
J 0
(-5250 2750);
PAINT ORANGE (-5250 2750);
DISPLAY INVISIBLE (-5250 2750);
FORCEPROP 1 LAST PATH I204
J 0
(-5252 2750);
DISPLAY 0.872340 (-5252 2750);
PAINT GREEN (-5252 2750);
DISPLAY INVISIBLE (-5252 2750);
FORCEPROP 1 LAST BODY_TYPE PLUMBING
J 0
(-5250 2700);
DISPLAY 0.872340 (-5250 2700);
PAINT GREEN (-5250 2700);
DISPLAY INVISIBLE (-5250 2700);
FORCEPROP 1 LAST HDL_TAP TRUE
J 0
(-4925 2625);
DISPLAY 0.872340 (-4925 2625);
PAINT ORANGE (-4925 2625);
DISPLAY INVISIBLE (-4925 2625);
FORCEADD CAP_A..2
(-4575 2050);
FORCEPROP 1 LAST LOCATION C2L16
J 1
(-4575 2150);
DISPLAY 0.617021 (-4575 2150);
PAINT AQUA (-4575 2150);
FORCEPROP 1 LAST PART_NUMBER A36096-045
J 1
(-4575 2100);
DISPLAY 0.617021 (-4575 2100);
PAINT BLUE (-4575 2100);
FORCEPROP 1 LAST TOLERANCE 10%
J 2
(-4575 1900);
DISPLAY 0.617021 (-4575 1900);
PAINT SKYBLUE (-4575 1900);
FORCEPROP 1 LAST PACK_TYPE 0402V
J 1
(-4575 1850);
DISPLAY 0.617021 (-4575 1850);
PAINT SKYBLUE (-4575 1850);
FORCEPROP 1 LAST VOLTAGE 25V
J 0
(-4575 1950);
DISPLAY 0.617021 (-4575 1950);
PAINT SKYBLUE (-4575 1950);
FORCEPROP 1 LAST MATERIAL X7R
J 0
(-4575 1900);
DISPLAY 0.617021 (-4575 1900);
PAINT SKYBLUE (-4575 1900);
FORCEPROP 1 LASTPIN (-4675 2050) $PN 1
J 0
(-4685 2065);
DISPLAY 0.617021 (-4685 2065);
PAINT ORANGE (-4685 2065);
FORCEPROP 1 LASTPIN (-4475 2050) $PN 2
J 0
(-4490 2065);
DISPLAY 0.617021 (-4490 2065);
PAINT ORANGE (-4490 2065);
FORCEPROP 1 LAST VALUE 0.01UF
J 2
(-4575 1950);
DISPLAY 0.617021 (-4575 1950);
PAINT SKYBLUE (-4575 1950);
FORCEPROP 2 LAST ROOM ST_SATA
J 0
(-4625 2200);
DISPLAY 1.361702 (-4625 2200);
PAINT ORANGE (-4625 2200);
DISPLAY INVISIBLE (-4625 2200);
FORCEPROP 2 LAST CDS_LOCATION C2L16
J 1
(-4575 2150);
DISPLAY 0.617021 (-4575 2150);
PAINT AQUA (-4575 2150);
DISPLAY INVISIBLE (-4575 2150);
FORCEPROP 2 LAST BOM_COST ST_SATA
J 0
(-4625 2150);
DISPLAY 1.361702 (-4625 2150);
PAINT ORANGE (-4625 2150);
DISPLAY INVISIBLE (-4625 2150);
FORCEPROP 2 LAST CDS_LIB dev_discrete
J 0
(-4575 2050);
PAINT ORANGE (-4575 2050);
DISPLAY INVISIBLE (-4575 2050);
FORCEPROP 2 LAST CDS_SEC 1
J 0
(-4575 2200);
PAINT ORANGE (-4575 2200);
DISPLAY INVISIBLE (-4575 2200);
FORCEPROP 2 LAST SEC_TYPE 0402V
J 0
(-4575 2300);
DISPLAY 1.021277 (-4575 2300);
PAINT ORANGE (-4575 2300);
DISPLAY INVISIBLE (-4575 2300);
FORCEPROP 2 LAST SEC 1
J 0
(-4575 2300);
DISPLAY 0.680851 (-4575 2300);
PAINT MONO (-4575 2300);
DISPLAY INVISIBLE (-4575 2300);
FORCEPROP 1 LAST PATH I205
J 0
(-4575 2250);
DISPLAY 0.978723 (-4575 2250);
PAINT WHITE (-4575 2250);
DISPLAY INVISIBLE (-4575 2250);
FORCEADD CAP_A..2
(-4575 1700);
FORCEPROP 1 LAST LOCATION C2L7
J 1
(-4575 1800);
DISPLAY 0.617021 (-4575 1800);
PAINT AQUA (-4575 1800);
FORCEPROP 1 LAST PART_NUMBER A36096-045
J 1
(-4575 1750);
DISPLAY 0.617021 (-4575 1750);
PAINT BLUE (-4575 1750);
FORCEPROP 1 LAST VALUE 0.01UF
J 2
(-4575 1600);
DISPLAY 0.617021 (-4575 1600);
PAINT SKYBLUE (-4575 1600);
FORCEPROP 1 LAST TOLERANCE 10%
J 2
(-4575 1550);
DISPLAY 0.617021 (-4575 1550);
PAINT SKYBLUE (-4575 1550);
FORCEPROP 1 LASTPIN (-4475 1700) $PN 2
J 0
(-4490 1715);
DISPLAY 0.617021 (-4490 1715);
PAINT ORANGE (-4490 1715);
FORCEPROP 1 LASTPIN (-4675 1700) $PN 1
J 0
(-4685 1715);
DISPLAY 0.617021 (-4685 1715);
PAINT ORANGE (-4685 1715);
FORCEPROP 1 LAST VOLTAGE 25V
J 0
(-4575 1600);
DISPLAY 0.617021 (-4575 1600);
PAINT SKYBLUE (-4575 1600);
FORCEPROP 1 LAST MATERIAL X7R
J 0
(-4575 1550);
DISPLAY 0.617021 (-4575 1550);
PAINT SKYBLUE (-4575 1550);
FORCEPROP 1 LAST PACK_TYPE 0402V
J 1
(-4575 1500);
DISPLAY 0.617021 (-4575 1500);
PAINT SKYBLUE (-4575 1500);
FORCEPROP 2 LAST ROOM ST_SATA
J 0
(-4625 1850);
DISPLAY 1.361702 (-4625 1850);
PAINT ORANGE (-4625 1850);
DISPLAY INVISIBLE (-4625 1850);
FORCEPROP 1 LAST PATH I206
J 0
(-4575 1900);
DISPLAY 0.978723 (-4575 1900);
PAINT WHITE (-4575 1900);
DISPLAY INVISIBLE (-4575 1900);
FORCEPROP 2 LAST SEC 1
J 0
(-4575 1950);
DISPLAY 0.680851 (-4575 1950);
PAINT MONO (-4575 1950);
DISPLAY INVISIBLE (-4575 1950);
FORCEPROP 2 LAST SEC_TYPE 0402V
J 0
(-4575 1950);
DISPLAY 1.021277 (-4575 1950);
PAINT ORANGE (-4575 1950);
DISPLAY INVISIBLE (-4575 1950);
FORCEPROP 2 LAST CDS_SEC 1
J 0
(-4575 1850);
PAINT ORANGE (-4575 1850);
DISPLAY INVISIBLE (-4575 1850);
FORCEPROP 2 LAST CDS_LIB dev_discrete
J 0
(-4575 1700);
PAINT ORANGE (-4575 1700);
DISPLAY INVISIBLE (-4575 1700);
FORCEPROP 2 LAST BOM_COST ST_SATA
J 0
(-4625 1800);
DISPLAY 1.361702 (-4625 1800);
PAINT ORANGE (-4625 1800);
DISPLAY INVISIBLE (-4625 1800);
FORCEPROP 2 LAST CDS_LOCATION C2L7
J 1
(-4575 1800);
DISPLAY 0.617021 (-4575 1800);
PAINT AQUA (-4575 1800);
DISPLAY INVISIBLE (-4575 1800);
FORCEADD CAP_A..2
(-4950 2400);
FORCEPROP 1 LAST LOCATION C2L9
J 1
(-4950 2500);
DISPLAY 0.617021 (-4950 2500);
PAINT AQUA (-4950 2500);
FORCEPROP 1 LAST VALUE 0.01UF
J 2
(-4950 2300);
DISPLAY 0.617021 (-4950 2300);
PAINT SKYBLUE (-4950 2300);
FORCEPROP 1 LAST TOLERANCE 10%
J 2
(-4950 2250);
DISPLAY 0.617021 (-4950 2250);
PAINT SKYBLUE (-4950 2250);
FORCEPROP 1 LAST PACK_TYPE 0402V
J 1
(-4950 2200);
DISPLAY 0.617021 (-4950 2200);
PAINT SKYBLUE (-4950 2200);
FORCEPROP 1 LAST VOLTAGE 25V
J 0
(-4950 2300);
DISPLAY 0.617021 (-4950 2300);
PAINT SKYBLUE (-4950 2300);
FORCEPROP 1 LAST MATERIAL X7R
J 0
(-4950 2250);
DISPLAY 0.617021 (-4950 2250);
PAINT SKYBLUE (-4950 2250);
FORCEPROP 1 LASTPIN (-5050 2400) $PN 1
J 0
(-5060 2415);
DISPLAY 0.617021 (-5060 2415);
PAINT ORANGE (-5060 2415);
FORCEPROP 1 LASTPIN (-4850 2400) $PN 2
J 0
(-4865 2415);
DISPLAY 0.617021 (-4865 2415);
PAINT ORANGE (-4865 2415);
FORCEPROP 1 LAST PART_NUMBER A36096-045
J 1
(-4950 2450);
DISPLAY 0.617021 (-4950 2450);
PAINT BLUE (-4950 2450);
FORCEPROP 2 LAST ROOM ST_SATA
J 0
(-5000 2550);
DISPLAY 1.361702 (-5000 2550);
PAINT ORANGE (-5000 2550);
DISPLAY INVISIBLE (-5000 2550);
FORCEPROP 2 LAST CDS_LOCATION C2L9
J 1
(-4950 2500);
DISPLAY 0.617021 (-4950 2500);
PAINT AQUA (-4950 2500);
DISPLAY INVISIBLE (-4950 2500);
FORCEPROP 2 LAST BOM_COST ST_SATA
J 0
(-5000 2500);
DISPLAY 1.361702 (-5000 2500);
PAINT ORANGE (-5000 2500);
DISPLAY INVISIBLE (-5000 2500);
FORCEPROP 2 LAST CDS_LIB dev_discrete
J 0
(-4950 2400);
PAINT ORANGE (-4950 2400);
DISPLAY INVISIBLE (-4950 2400);
FORCEPROP 2 LAST CDS_SEC 1
J 0
(-4950 2550);
PAINT ORANGE (-4950 2550);
DISPLAY INVISIBLE (-4950 2550);
FORCEPROP 2 LAST SEC_TYPE 0402V
J 0
(-4950 2650);
DISPLAY 1.021277 (-4950 2650);
PAINT ORANGE (-4950 2650);
DISPLAY INVISIBLE (-4950 2650);
FORCEPROP 2 LAST SEC 1
J 0
(-4950 2650);
DISPLAY 0.680851 (-4950 2650);
PAINT MONO (-4950 2650);
DISPLAY INVISIBLE (-4950 2650);
FORCEPROP 1 LAST PATH I207
J 0
(-4950 2600);
DISPLAY 0.978723 (-4950 2600);
PAINT WHITE (-4950 2600);
DISPLAY INVISIBLE (-4950 2600);
FORCEADD CAP_A..2
(-4975 1850);
FORCEPROP 1 LAST LOCATION C2L14
J 1
(-4975 1950);
DISPLAY 0.617021 (-4975 1950);
PAINT AQUA (-4975 1950);
FORCEPROP 1 LAST PART_NUMBER A36096-045
J 1
(-4975 1900);
DISPLAY 0.617021 (-4975 1900);
PAINT BLUE (-4975 1900);
FORCEPROP 1 LAST VALUE 0.01UF
J 2
(-4975 1750);
DISPLAY 0.617021 (-4975 1750);
PAINT SKYBLUE (-4975 1750);
FORCEPROP 1 LAST TOLERANCE 10%
J 2
(-4975 1700);
DISPLAY 0.617021 (-4975 1700);
PAINT SKYBLUE (-4975 1700);
FORCEPROP 1 LAST VOLTAGE 25V
J 0
(-4975 1750);
DISPLAY 0.617021 (-4975 1750);
PAINT SKYBLUE (-4975 1750);
FORCEPROP 1 LASTPIN (-5075 1850) $PN 1
J 0
(-5085 1865);
DISPLAY 0.617021 (-5085 1865);
PAINT ORANGE (-5085 1865);
FORCEPROP 1 LASTPIN (-4875 1850) $PN 2
J 0
(-4890 1865);
DISPLAY 0.617021 (-4890 1865);
PAINT ORANGE (-4890 1865);
FORCEPROP 1 LAST PACK_TYPE 0402V
J 1
(-4975 1650);
DISPLAY 0.617021 (-4975 1650);
PAINT SKYBLUE (-4975 1650);
FORCEPROP 1 LAST MATERIAL X7R
J 0
(-4975 1700);
DISPLAY 0.617021 (-4975 1700);
PAINT SKYBLUE (-4975 1700);
FORCEPROP 2 LAST ROOM ST_SATA
J 0
(-5025 2000);
DISPLAY 1.361702 (-5025 2000);
PAINT ORANGE (-5025 2000);
DISPLAY INVISIBLE (-5025 2000);
FORCEPROP 2 LAST CDS_LOCATION C2L14
J 1
(-4975 1950);
DISPLAY 0.617021 (-4975 1950);
PAINT AQUA (-4975 1950);
DISPLAY INVISIBLE (-4975 1950);
FORCEPROP 2 LAST BOM_COST ST_SATA
J 0
(-5025 1950);
DISPLAY 1.361702 (-5025 1950);
PAINT ORANGE (-5025 1950);
DISPLAY INVISIBLE (-5025 1950);
FORCEPROP 2 LAST CDS_LIB dev_discrete
J 0
(-4975 1850);
PAINT ORANGE (-4975 1850);
DISPLAY INVISIBLE (-4975 1850);
FORCEPROP 2 LAST CDS_SEC 1
J 0
(-4975 2000);
PAINT ORANGE (-4975 2000);
DISPLAY INVISIBLE (-4975 2000);
FORCEPROP 2 LAST SEC_TYPE 0402V
J 0
(-4975 2100);
DISPLAY 1.021277 (-4975 2100);
PAINT ORANGE (-4975 2100);
DISPLAY INVISIBLE (-4975 2100);
FORCEPROP 2 LAST SEC 1
J 0
(-4975 2100);
DISPLAY 0.680851 (-4975 2100);
PAINT MONO (-4975 2100);
DISPLAY INVISIBLE (-4975 2100);
FORCEPROP 1 LAST PATH I208
J 0
(-4975 2050);
DISPLAY 0.978723 (-4975 2050);
PAINT WHITE (-4975 2050);
DISPLAY INVISIBLE (-4975 2050);
FORCEADD CAP_A..2
(-4975 1500);
FORCEPROP 1 LAST VALUE 0.01UF
J 2
(-4975 1400);
DISPLAY 0.617021 (-4975 1400);
PAINT SKYBLUE (-4975 1400);
FORCEPROP 1 LAST TOLERANCE 10%
J 2
(-4975 1350);
DISPLAY 0.617021 (-4975 1350);
PAINT SKYBLUE (-4975 1350);
FORCEPROP 1 LAST PACK_TYPE 0402V
J 1
(-4975 1300);
DISPLAY 0.617021 (-4975 1300);
PAINT SKYBLUE (-4975 1300);
FORCEPROP 1 LAST VOLTAGE 25V
J 0
(-4975 1400);
DISPLAY 0.617021 (-4975 1400);
PAINT SKYBLUE (-4975 1400);
FORCEPROP 1 LAST MATERIAL X7R
J 0
(-4975 1350);
DISPLAY 0.617021 (-4975 1350);
PAINT SKYBLUE (-4975 1350);
FORCEPROP 1 LASTPIN (-5075 1500) $PN 1
J 0
(-5085 1515);
DISPLAY 0.617021 (-5085 1515);
PAINT ORANGE (-5085 1515);
FORCEPROP 1 LASTPIN (-4875 1500) $PN 2
J 0
(-4890 1515);
DISPLAY 0.617021 (-4890 1515);
PAINT ORANGE (-4890 1515);
FORCEPROP 1 LAST PART_NUMBER A36096-045
J 1
(-4975 1550);
DISPLAY 0.617021 (-4975 1550);
PAINT BLUE (-4975 1550);
FORCEPROP 1 LAST LOCATION C2L5
J 1
(-4975 1600);
DISPLAY 0.617021 (-4975 1600);
PAINT AQUA (-4975 1600);
FORCEPROP 2 LAST ROOM ST_SATA
J 0
(-5025 1650);
DISPLAY 1.361702 (-5025 1650);
PAINT ORANGE (-5025 1650);
DISPLAY INVISIBLE (-5025 1650);
FORCEPROP 2 LAST CDS_LOCATION C2L5
J 1
(-4975 1600);
DISPLAY 0.617021 (-4975 1600);
PAINT AQUA (-4975 1600);
DISPLAY INVISIBLE (-4975 1600);
FORCEPROP 2 LAST BOM_COST ST_SATA
J 0
(-5025 1600);
DISPLAY 1.361702 (-5025 1600);
PAINT ORANGE (-5025 1600);
DISPLAY INVISIBLE (-5025 1600);
FORCEPROP 2 LAST CDS_LIB dev_discrete
J 0
(-4975 1500);
PAINT ORANGE (-4975 1500);
DISPLAY INVISIBLE (-4975 1500);
FORCEPROP 2 LAST CDS_SEC 1
J 0
(-4975 1650);
PAINT ORANGE (-4975 1650);
DISPLAY INVISIBLE (-4975 1650);
FORCEPROP 2 LAST SEC_TYPE 0402V
J 0
(-4975 1750);
DISPLAY 1.021277 (-4975 1750);
PAINT ORANGE (-4975 1750);
DISPLAY INVISIBLE (-4975 1750);
FORCEPROP 2 LAST SEC 1
J 0
(-4975 1750);
DISPLAY 0.680851 (-4975 1750);
PAINT MONO (-4975 1750);
DISPLAY INVISIBLE (-4975 1750);
FORCEPROP 1 LAST PATH I209
J 0
(-4975 1700);
DISPLAY 0.978723 (-4975 1700);
PAINT WHITE (-4975 1700);
DISPLAY INVISIBLE (-4975 1700);
FORCEADD TAP..6
(-5250 2400);
FORCEPROP 3 LASTPIN (-5200 2400) SIG_NAME SATA6G_PCH_PCIE_UP_SATA_RXN<5>
J 0
(-5190 2410);
DISPLAY 0.659574 (-5190 2410);
PAINT MONO (-5190 2410);
DISPLAY INVISIBLE (-5190 2410);
FORCEPROP 1 LASTPIN (-5200 2400) BN 5
J 0
(-5252 2408);
DISPLAY 0.617021 (-5252 2408);
PAINT GREEN (-5252 2408);
FORCEPROP 2 LAST CDS_LIB mstr_standard
J 0
(-5250 2400);
PAINT ORANGE (-5250 2400);
DISPLAY INVISIBLE (-5250 2400);
FORCEPROP 1 LAST PATH I210
J 0
(-5252 2400);
DISPLAY 0.872340 (-5252 2400);
PAINT GREEN (-5252 2400);
DISPLAY INVISIBLE (-5252 2400);
FORCEPROP 1 LAST BODY_TYPE PLUMBING
J 0
(-5250 2350);
DISPLAY 0.872340 (-5250 2350);
PAINT GREEN (-5250 2350);
DISPLAY INVISIBLE (-5250 2350);
FORCEPROP 1 LAST HDL_TAP TRUE
J 0
(-4925 2275);
DISPLAY 0.872340 (-4925 2275);
PAINT ORANGE (-4925 2275);
DISPLAY INVISIBLE (-4925 2275);
FORCEADD TAP..6
(-5400 2050);
FORCEPROP 3 LASTPIN (-5350 2050) SIG_NAME SATA6G_PCH_PCIE_UP_SATA_RXP<6>
J 0
(-5340 2060);
DISPLAY 0.659574 (-5340 2060);
PAINT MONO (-5340 2060);
DISPLAY INVISIBLE (-5340 2060);
FORCEPROP 1 LASTPIN (-5350 2050) BN 6
J 0
(-5402 2058);
DISPLAY 0.617021 (-5402 2058);
PAINT GREEN (-5402 2058);
FORCEPROP 2 LAST CDS_LIB mstr_standard
J 0
(-5400 2050);
PAINT ORANGE (-5400 2050);
DISPLAY INVISIBLE (-5400 2050);
FORCEPROP 1 LAST PATH I211
J 0
(-5402 2050);
DISPLAY 0.872340 (-5402 2050);
PAINT GREEN (-5402 2050);
DISPLAY INVISIBLE (-5402 2050);
FORCEPROP 1 LAST BODY_TYPE PLUMBING
J 0
(-5400 2000);
DISPLAY 0.872340 (-5400 2000);
PAINT GREEN (-5400 2000);
DISPLAY INVISIBLE (-5400 2000);
FORCEPROP 1 LAST HDL_TAP TRUE
J 0
(-5075 1925);
DISPLAY 0.872340 (-5075 1925);
PAINT ORANGE (-5075 1925);
DISPLAY INVISIBLE (-5075 1925);
FORCEADD TAP..6
(-5400 1700);
FORCEPROP 3 LASTPIN (-5350 1700) SIG_NAME SATA6G_PCH_PCIE_UP_SATA_RXP<7>
J 0
(-5340 1710);
DISPLAY 0.659574 (-5340 1710);
PAINT MONO (-5340 1710);
DISPLAY INVISIBLE (-5340 1710);
FORCEPROP 1 LASTPIN (-5350 1700) BN 7
J 0
(-5402 1708);
DISPLAY 0.617021 (-5402 1708);
PAINT GREEN (-5402 1708);
FORCEPROP 1 LAST PATH I212
J 0
(-5402 1700);
DISPLAY 0.872340 (-5402 1700);
PAINT GREEN (-5402 1700);
DISPLAY INVISIBLE (-5402 1700);
FORCEPROP 2 LAST CDS_LIB mstr_standard
J 0
(-5400 1700);
PAINT ORANGE (-5400 1700);
DISPLAY INVISIBLE (-5400 1700);
FORCEPROP 1 LAST BODY_TYPE PLUMBING
J 0
(-5400 1650);
DISPLAY 0.872340 (-5400 1650);
PAINT GREEN (-5400 1650);
DISPLAY INVISIBLE (-5400 1650);
FORCEPROP 1 LAST HDL_TAP TRUE
J 0
(-5075 1575);
DISPLAY 0.872340 (-5075 1575);
PAINT ORANGE (-5075 1575);
DISPLAY INVISIBLE (-5075 1575);
FORCEADD TAP..6
(-5250 1850);
FORCEPROP 3 LASTPIN (-5200 1850) SIG_NAME SATA6G_PCH_PCIE_UP_SATA_RXN<6>
J 0
(-5190 1860);
DISPLAY 0.659574 (-5190 1860);
PAINT MONO (-5190 1860);
DISPLAY INVISIBLE (-5190 1860);
FORCEPROP 1 LASTPIN (-5200 1850) BN 6
J 0
(-5252 1858);
DISPLAY 0.617021 (-5252 1858);
PAINT GREEN (-5252 1858);
FORCEPROP 2 LAST CDS_LIB mstr_standard
J 0
(-5250 1850);
PAINT ORANGE (-5250 1850);
DISPLAY INVISIBLE (-5250 1850);
FORCEPROP 1 LAST PATH I213
J 0
(-5252 1850);
DISPLAY 0.872340 (-5252 1850);
PAINT GREEN (-5252 1850);
DISPLAY INVISIBLE (-5252 1850);
FORCEPROP 1 LAST BODY_TYPE PLUMBING
J 0
(-5250 1800);
DISPLAY 0.872340 (-5250 1800);
PAINT GREEN (-5250 1800);
DISPLAY INVISIBLE (-5250 1800);
FORCEPROP 1 LAST HDL_TAP TRUE
J 0
(-4925 1725);
DISPLAY 0.872340 (-4925 1725);
PAINT ORANGE (-4925 1725);
DISPLAY INVISIBLE (-4925 1725);
FORCEADD TAP..6
(-5250 1500);
FORCEPROP 3 LASTPIN (-5200 1500) SIG_NAME SATA6G_PCH_PCIE_UP_SATA_RXN<7>
J 0
(-5190 1510);
DISPLAY 0.659574 (-5190 1510);
PAINT MONO (-5190 1510);
DISPLAY INVISIBLE (-5190 1510);
FORCEPROP 1 LASTPIN (-5200 1500) BN 7
J 0
(-5252 1508);
DISPLAY 0.617021 (-5252 1508);
PAINT GREEN (-5252 1508);
FORCEPROP 2 LAST CDS_LIB mstr_standard
J 0
(-5250 1500);
PAINT ORANGE (-5250 1500);
DISPLAY INVISIBLE (-5250 1500);
FORCEPROP 1 LAST PATH I214
J 0
(-5252 1500);
DISPLAY 0.872340 (-5252 1500);
PAINT GREEN (-5252 1500);
DISPLAY INVISIBLE (-5252 1500);
FORCEPROP 1 LAST BODY_TYPE PLUMBING
J 0
(-5250 1450);
DISPLAY 0.872340 (-5250 1450);
PAINT GREEN (-5250 1450);
DISPLAY INVISIBLE (-5250 1450);
FORCEPROP 1 LAST HDL_TAP TRUE
J 0
(-4925 1375);
DISPLAY 0.872340 (-4925 1375);
PAINT ORANGE (-4925 1375);
DISPLAY INVISIBLE (-4925 1375);
FORCEADD TAP..1
(1300 1550);
FORCEPROP 3 LASTPIN (1250 1550) SIG_NAME SATA6G_PCH_PCIE_UP_SATA_TXN<7>
J 0
(1260 1560);
DISPLAY 0.659574 (1260 1560);
PAINT MONO (1260 1560);
DISPLAY INVISIBLE (1260 1560);
FORCEPROP 1 LASTPIN (1250 1550) BN 7
J 0
(1238 1558);
DISPLAY 0.617021 (1238 1558);
PAINT GREEN (1238 1558);
FORCEPROP 2 LAST CDS_LIB mstr_standard
J 0
(1300 1550);
PAINT ORANGE (1300 1550);
DISPLAY INVISIBLE (1300 1550);
FORCEPROP 1 LAST PATH I215
J 0
(1298 1550);
DISPLAY 0.872340 (1298 1550);
PAINT GREEN (1298 1550);
DISPLAY INVISIBLE (1298 1550);
FORCEPROP 1 LAST BODY_TYPE PLUMBING
J 0
(1300 1600);
DISPLAY 0.872340 (1300 1600);
PAINT GREEN (1300 1600);
DISPLAY INVISIBLE (1300 1600);
FORCEPROP 1 LAST HDL_TAP TRUE
J 0
(1625 1425);
DISPLAY 0.872340 (1625 1425);
PAINT ORANGE (1625 1425);
DISPLAY INVISIBLE (1625 1425);
FORCEADD TAP..1
(1450 4675);
FORCEPROP 3 LASTPIN (1400 4675) SIG_NAME SATA6G_PCH_PCIE_UP_SATA_TXP<0>
J 0
(1410 4685);
DISPLAY 0.659574 (1410 4685);
PAINT MONO (1410 4685);
DISPLAY INVISIBLE (1410 4685);
FORCEPROP 1 LASTPIN (1400 4675) BN 0
J 0
(1388 4683);
DISPLAY 0.617021 (1388 4683);
PAINT GREEN (1388 4683);
FORCEPROP 2 LAST CDS_LIB mstr_standard
J 0
(1450 4675);
PAINT ORANGE (1450 4675);
DISPLAY INVISIBLE (1450 4675);
FORCEPROP 1 LAST PATH I216
J 0
(1448 4675);
DISPLAY 0.872340 (1448 4675);
PAINT GREEN (1448 4675);
DISPLAY INVISIBLE (1448 4675);
FORCEPROP 1 LAST BODY_TYPE PLUMBING
J 0
(1450 4725);
DISPLAY 0.872340 (1450 4725);
PAINT GREEN (1450 4725);
DISPLAY INVISIBLE (1450 4725);
FORCEPROP 1 LAST HDL_TAP TRUE
J 0
(1775 4550);
DISPLAY 0.872340 (1775 4550);
PAINT ORANGE (1775 4550);
DISPLAY INVISIBLE (1775 4550);
FORCEADD TAP..1
(1450 4325);
FORCEPROP 3 LASTPIN (1400 4325) SIG_NAME SATA6G_PCH_PCIE_UP_SATA_TXP<1>
J 0
(1410 4335);
DISPLAY 0.659574 (1410 4335);
PAINT MONO (1410 4335);
DISPLAY INVISIBLE (1410 4335);
FORCEPROP 1 LASTPIN (1400 4325) BN 1
J 0
(1388 4333);
DISPLAY 0.617021 (1388 4333);
PAINT GREEN (1388 4333);
FORCEPROP 2 LAST CDS_LIB mstr_standard
J 0
(1450 4325);
PAINT ORANGE (1450 4325);
DISPLAY INVISIBLE (1450 4325);
FORCEPROP 1 LAST PATH I217
J 0
(1448 4325);
DISPLAY 0.872340 (1448 4325);
PAINT GREEN (1448 4325);
DISPLAY INVISIBLE (1448 4325);
FORCEPROP 1 LAST BODY_TYPE PLUMBING
J 0
(1450 4375);
DISPLAY 0.872340 (1450 4375);
PAINT GREEN (1450 4375);
DISPLAY INVISIBLE (1450 4375);
FORCEPROP 1 LAST HDL_TAP TRUE
J 0
(1775 4200);
DISPLAY 0.872340 (1775 4200);
PAINT ORANGE (1775 4200);
DISPLAY INVISIBLE (1775 4200);
FORCEADD TAP..1
(1300 4175);
FORCEPROP 3 LASTPIN (1250 4175) SIG_NAME SATA6G_PCH_PCIE_UP_SATA_TXN<1>
J 0
(1260 4185);
DISPLAY 0.659574 (1260 4185);
PAINT MONO (1260 4185);
DISPLAY INVISIBLE (1260 4185);
FORCEPROP 1 LASTPIN (1250 4175) BN 1
J 0
(1238 4183);
DISPLAY 0.617021 (1238 4183);
PAINT GREEN (1238 4183);
FORCEPROP 1 LAST PATH I218
J 0
(1298 4175);
DISPLAY 0.872340 (1298 4175);
PAINT GREEN (1298 4175);
DISPLAY INVISIBLE (1298 4175);
FORCEPROP 2 LAST CDS_LIB mstr_standard
J 0
(1300 4175);
PAINT ORANGE (1300 4175);
DISPLAY INVISIBLE (1300 4175);
FORCEPROP 1 LAST BODY_TYPE PLUMBING
J 0
(1300 4225);
DISPLAY 0.872340 (1300 4225);
PAINT GREEN (1300 4225);
DISPLAY INVISIBLE (1300 4225);
FORCEPROP 1 LAST HDL_TAP TRUE
J 0
(1625 4050);
DISPLAY 0.872340 (1625 4050);
PAINT ORANGE (1625 4050);
DISPLAY INVISIBLE (1625 4050);
FORCEADD TAP..1
(1300 4525);
FORCEPROP 3 LASTPIN (1250 4525) SIG_NAME SATA6G_PCH_PCIE_UP_SATA_TXN<0>
J 0
(1260 4535);
DISPLAY 0.659574 (1260 4535);
PAINT MONO (1260 4535);
DISPLAY INVISIBLE (1260 4535);
FORCEPROP 1 LASTPIN (1250 4525) BN 0
J 0
(1238 4533);
DISPLAY 0.617021 (1238 4533);
PAINT GREEN (1238 4533);
FORCEPROP 2 LAST CDS_LIB mstr_standard
J 0
(1300 4525);
PAINT ORANGE (1300 4525);
DISPLAY INVISIBLE (1300 4525);
FORCEPROP 1 LAST PATH I219
J 0
(1298 4525);
DISPLAY 0.872340 (1298 4525);
PAINT GREEN (1298 4525);
DISPLAY INVISIBLE (1298 4525);
FORCEPROP 1 LAST BODY_TYPE PLUMBING
J 0
(1300 4575);
DISPLAY 0.872340 (1300 4575);
PAINT GREEN (1300 4575);
DISPLAY INVISIBLE (1300 4575);
FORCEPROP 1 LAST HDL_TAP TRUE
J 0
(1625 4400);
DISPLAY 0.872340 (1625 4400);
PAINT ORANGE (1625 4400);
DISPLAY INVISIBLE (1625 4400);
FORCEADD CAP_A..2
(1025 4525);
FORCEPROP 1 LAST LOCATION C2L40
J 1
(1025 4625);
DISPLAY 0.617021 (1025 4625);
PAINT AQUA (1025 4625);
FORCEPROP 1 LAST PART_NUMBER A36096-045
J 1
(1025 4575);
DISPLAY 0.617021 (1025 4575);
PAINT BLUE (1025 4575);
FORCEPROP 1 LAST VALUE 0.01UF
J 2
(1025 4425);
DISPLAY 0.617021 (1025 4425);
PAINT SKYBLUE (1025 4425);
FORCEPROP 1 LAST TOLERANCE 10%
J 2
(1025 4375);
DISPLAY 0.617021 (1025 4375);
PAINT SKYBLUE (1025 4375);
FORCEPROP 1 LAST PACK_TYPE 0402V
J 1
(1025 4325);
DISPLAY 0.617021 (1025 4325);
PAINT SKYBLUE (1025 4325);
FORCEPROP 1 LAST VOLTAGE 25V
J 0
(1025 4425);
DISPLAY 0.617021 (1025 4425);
PAINT SKYBLUE (1025 4425);
FORCEPROP 1 LAST MATERIAL X7R
J 0
(1025 4375);
DISPLAY 0.617021 (1025 4375);
PAINT SKYBLUE (1025 4375);
FORCEPROP 1 LASTPIN (925 4525) $PN 1
J 0
(915 4540);
DISPLAY 0.617021 (915 4540);
PAINT ORANGE (915 4540);
FORCEPROP 1 LASTPIN (1125 4525) $PN 2
J 0
(1110 4540);
DISPLAY 0.617021 (1110 4540);
PAINT ORANGE (1110 4540);
FORCEPROP 2 LAST ROOM ST_SATA
J 0
(925 4675);
DISPLAY 1.361702 (925 4675);
PAINT ORANGE (925 4675);
DISPLAY INVISIBLE (925 4675);
FORCEPROP 2 LAST CDS_LOCATION C2L40
J 1
(1025 4625);
DISPLAY 0.617021 (1025 4625);
PAINT AQUA (1025 4625);
DISPLAY INVISIBLE (1025 4625);
FORCEPROP 2 LAST BOM_COST ST_SATA
J 0
(925 4675);
DISPLAY 1.361702 (925 4675);
PAINT ORANGE (925 4675);
DISPLAY INVISIBLE (925 4675);
FORCEPROP 2 LAST CDS_LIB dev_discrete
J 0
(1025 4525);
PAINT ORANGE (1025 4525);
DISPLAY INVISIBLE (1025 4525);
FORCEPROP 2 LAST CDS_SEC 1
J 0
(1025 4675);
PAINT ORANGE (1025 4675);
DISPLAY INVISIBLE (1025 4675);
FORCEPROP 2 LAST SEC_TYPE 0402V
J 0
(1025 4775);
DISPLAY 1.021277 (1025 4775);
PAINT ORANGE (1025 4775);
DISPLAY INVISIBLE (1025 4775);
FORCEPROP 2 LAST SEC 1
J 0
(1025 4775);
DISPLAY 0.680851 (1025 4775);
PAINT MONO (1025 4775);
DISPLAY INVISIBLE (1025 4775);
FORCEPROP 1 LAST PATH I220
J 0
(1025 4725);
DISPLAY 0.978723 (1025 4725);
PAINT WHITE (1025 4725);
DISPLAY INVISIBLE (1025 4725);
FORCEADD CAP_A..2
(650 4675);
FORCEPROP 1 LAST LOCATION C2L39
J 1
(650 4775);
DISPLAY 0.617021 (650 4775);
PAINT AQUA (650 4775);
FORCEPROP 1 LAST TOLERANCE 10%
J 2
(650 4525);
DISPLAY 0.617021 (650 4525);
PAINT SKYBLUE (650 4525);
FORCEPROP 1 LAST VOLTAGE 25V
J 0
(650 4575);
DISPLAY 0.617021 (650 4575);
PAINT SKYBLUE (650 4575);
FORCEPROP 1 LAST MATERIAL X7R
J 0
(650 4525);
DISPLAY 0.617021 (650 4525);
PAINT SKYBLUE (650 4525);
FORCEPROP 1 LASTPIN (550 4675) $PN 1
J 0
(540 4690);
DISPLAY 0.617021 (540 4690);
PAINT ORANGE (540 4690);
FORCEPROP 1 LASTPIN (750 4675) $PN 2
J 0
(735 4690);
DISPLAY 0.617021 (735 4690);
PAINT ORANGE (735 4690);
FORCEPROP 1 LAST PACK_TYPE 0402V
J 1
(650 4475);
DISPLAY 0.617021 (650 4475);
PAINT SKYBLUE (650 4475);
FORCEPROP 1 LAST VALUE 0.01UF
J 2
(650 4575);
DISPLAY 0.617021 (650 4575);
PAINT SKYBLUE (650 4575);
FORCEPROP 1 LAST PART_NUMBER A36096-045
J 1
(650 4725);
DISPLAY 0.617021 (650 4725);
PAINT BLUE (650 4725);
FORCEPROP 2 LAST ROOM ST_SATA
J 0
(600 4825);
DISPLAY 1.361702 (600 4825);
PAINT ORANGE (600 4825);
DISPLAY INVISIBLE (600 4825);
FORCEPROP 2 LAST CDS_LOCATION C2L39
J 1
(650 4775);
DISPLAY 0.617021 (650 4775);
PAINT AQUA (650 4775);
DISPLAY INVISIBLE (650 4775);
FORCEPROP 2 LAST BOM_COST ST_SATA
J 0
(600 4825);
DISPLAY 1.361702 (600 4825);
PAINT ORANGE (600 4825);
DISPLAY INVISIBLE (600 4825);
FORCEPROP 2 LAST CDS_LIB dev_discrete
J 0
(650 4675);
PAINT ORANGE (650 4675);
DISPLAY INVISIBLE (650 4675);
FORCEPROP 2 LAST CDS_SEC 1
J 0
(650 4825);
PAINT ORANGE (650 4825);
DISPLAY INVISIBLE (650 4825);
FORCEPROP 2 LAST SEC_TYPE 0402V
J 0
(650 4925);
DISPLAY 1.021277 (650 4925);
PAINT ORANGE (650 4925);
DISPLAY INVISIBLE (650 4925);
FORCEPROP 2 LAST SEC 1
J 0
(650 4925);
DISPLAY 0.680851 (650 4925);
PAINT MONO (650 4925);
DISPLAY INVISIBLE (650 4925);
FORCEPROP 1 LAST PATH I221
J 0
(650 4875);
DISPLAY 0.978723 (650 4875);
PAINT WHITE (650 4875);
DISPLAY INVISIBLE (650 4875);
FORCEADD CAP_A..2
(650 4325);
FORCEPROP 1 LAST TOLERANCE 10%
J 2
(650 4175);
DISPLAY 0.617021 (650 4175);
PAINT SKYBLUE (650 4175);
FORCEPROP 1 LAST PACK_TYPE 0402V
J 1
(650 4125);
DISPLAY 0.617021 (650 4125);
PAINT SKYBLUE (650 4125);
FORCEPROP 1 LAST MATERIAL X7R
J 0
(650 4175);
DISPLAY 0.617021 (650 4175);
PAINT SKYBLUE (650 4175);
FORCEPROP 1 LASTPIN (750 4325) $PN 2
J 0
(735 4340);
DISPLAY 0.617021 (735 4340);
PAINT ORANGE (735 4340);
FORCEPROP 1 LASTPIN (550 4325) $PN 1
J 0
(540 4340);
DISPLAY 0.617021 (540 4340);
PAINT ORANGE (540 4340);
FORCEPROP 1 LAST VOLTAGE 25V
J 0
(650 4225);
DISPLAY 0.617021 (650 4225);
PAINT SKYBLUE (650 4225);
FORCEPROP 1 LAST VALUE 0.01UF
J 2
(650 4225);
DISPLAY 0.617021 (650 4225);
PAINT SKYBLUE (650 4225);
FORCEPROP 1 LAST PART_NUMBER A36096-045
J 1
(650 4375);
DISPLAY 0.617021 (650 4375);
PAINT BLUE (650 4375);
FORCEPROP 1 LAST LOCATION C2L43
J 1
(650 4425);
DISPLAY 0.617021 (650 4425);
PAINT AQUA (650 4425);
FORCEPROP 2 LAST ROOM ST_SATA
J 0
(550 4475);
DISPLAY 1.361702 (550 4475);
PAINT ORANGE (550 4475);
DISPLAY INVISIBLE (550 4475);
FORCEPROP 2 LAST CDS_LOCATION C2L43
J 1
(650 4425);
DISPLAY 0.617021 (650 4425);
PAINT AQUA (650 4425);
DISPLAY INVISIBLE (650 4425);
FORCEPROP 2 LAST BOM_COST ST_SATA
J 0
(550 4475);
DISPLAY 1.361702 (550 4475);
PAINT ORANGE (550 4475);
DISPLAY INVISIBLE (550 4475);
FORCEPROP 2 LAST CDS_LIB dev_discrete
J 0
(650 4325);
PAINT ORANGE (650 4325);
DISPLAY INVISIBLE (650 4325);
FORCEPROP 2 LAST CDS_SEC 1
J 0
(650 4475);
PAINT ORANGE (650 4475);
DISPLAY INVISIBLE (650 4475);
FORCEPROP 2 LAST SEC_TYPE 0402V
J 0
(650 4575);
DISPLAY 1.021277 (650 4575);
PAINT ORANGE (650 4575);
DISPLAY INVISIBLE (650 4575);
FORCEPROP 2 LAST SEC 1
J 0
(650 4575);
DISPLAY 0.680851 (650 4575);
PAINT MONO (650 4575);
DISPLAY INVISIBLE (650 4575);
FORCEPROP 1 LAST PATH I222
J 0
(650 4525);
DISPLAY 0.978723 (650 4525);
PAINT WHITE (650 4525);
DISPLAY INVISIBLE (650 4525);
FORCEADD OFFPAGE..1
(25 5225);
FORCEPROP 2 LAST $XR0 116 
J 0
(-227 5225);
DISPLAY 0.638298 (-227 5225);
PAINT MONO (-227 5225);
FORCEPROP 2 LAST CDS_LIB mstr_standard
J 0
(25 5225);
PAINT ORANGE (25 5225);
DISPLAY INVISIBLE (25 5225);
FORCEPROP 2 LAST PATH I223
J 0
(-225 5275);
DISPLAY 1.021277 (-225 5275);
PAINT ORANGE (-225 5275);
DISPLAY INVISIBLE (-225 5275);
FORCEPROP 1 LAST OFFPAGE TRUE
J 0
(350 5100);
DISPLAY 0.872340 (350 5100);
PAINT GREEN (350 5100);
DISPLAY INVISIBLE (350 5100);
FORCEPROP 1 LAST COMMENT_BODY TRUE
J 0
(150 5125);
DISPLAY 0.872340 (150 5125);
PAINT GREEN (150 5125);
DISPLAY INVISIBLE (150 5125);
FORCEADD OFFPAGE..1
(25 5075);
FORCEPROP 2 LAST $XR0 116 
J 0
(-227 5075);
DISPLAY 0.638298 (-227 5075);
PAINT MONO (-227 5075);
FORCEPROP 2 LAST CDS_LIB mstr_standard
J 0
(25 5075);
PAINT ORANGE (25 5075);
DISPLAY INVISIBLE (25 5075);
FORCEPROP 2 LAST PATH I224
J 0
(-225 5125);
DISPLAY 1.021277 (-225 5125);
PAINT ORANGE (-225 5125);
DISPLAY INVISIBLE (-225 5125);
FORCEPROP 1 LAST OFFPAGE TRUE
J 0
(350 4950);
DISPLAY 0.872340 (350 4950);
PAINT GREEN (350 4950);
DISPLAY INVISIBLE (350 4950);
FORCEPROP 1 LAST COMMENT_BODY TRUE
J 0
(150 4975);
DISPLAY 0.872340 (150 4975);
PAINT GREEN (150 4975);
DISPLAY INVISIBLE (150 4975);
FORCEADD CAP_A..2
(1025 4175);
FORCEPROP 1 LAST LOCATION C2L44
J 1
(1025 4275);
DISPLAY 0.617021 (1025 4275);
PAINT AQUA (1025 4275);
FORCEPROP 1 LAST PART_NUMBER A36096-045
J 1
(1025 4225);
DISPLAY 0.617021 (1025 4225);
PAINT BLUE (1025 4225);
FORCEPROP 1 LAST VALUE 0.01UF
J 2
(1025 4075);
DISPLAY 0.617021 (1025 4075);
PAINT SKYBLUE (1025 4075);
FORCEPROP 1 LAST TOLERANCE 10%
J 2
(1025 4025);
DISPLAY 0.617021 (1025 4025);
PAINT SKYBLUE (1025 4025);
FORCEPROP 1 LAST PACK_TYPE 0402V
J 1
(1025 3975);
DISPLAY 0.617021 (1025 3975);
PAINT SKYBLUE (1025 3975);
FORCEPROP 1 LAST VOLTAGE 25V
J 0
(1025 4075);
DISPLAY 0.617021 (1025 4075);
PAINT SKYBLUE (1025 4075);
FORCEPROP 1 LAST MATERIAL X7R
J 0
(1025 4025);
DISPLAY 0.617021 (1025 4025);
PAINT SKYBLUE (1025 4025);
FORCEPROP 1 LASTPIN (1125 4175) $PN 2
J 0
(1110 4190);
DISPLAY 0.617021 (1110 4190);
PAINT ORANGE (1110 4190);
FORCEPROP 1 LASTPIN (925 4175) $PN 1
J 0
(915 4190);
DISPLAY 0.617021 (915 4190);
PAINT ORANGE (915 4190);
FORCEPROP 2 LAST ROOM ST_SATA
J 0
(925 4325);
DISPLAY 1.361702 (925 4325);
PAINT ORANGE (925 4325);
DISPLAY INVISIBLE (925 4325);
FORCEPROP 1 LAST PATH I228
J 0
(1025 4375);
DISPLAY 0.978723 (1025 4375);
PAINT WHITE (1025 4375);
DISPLAY INVISIBLE (1025 4375);
FORCEPROP 2 LAST SEC 1
J 0
(1025 4425);
DISPLAY 0.680851 (1025 4425);
PAINT MONO (1025 4425);
DISPLAY INVISIBLE (1025 4425);
FORCEPROP 2 LAST SEC_TYPE 0402V
J 0
(1025 4425);
DISPLAY 1.021277 (1025 4425);
PAINT ORANGE (1025 4425);
DISPLAY INVISIBLE (1025 4425);
FORCEPROP 2 LAST CDS_SEC 1
J 0
(1025 4325);
PAINT ORANGE (1025 4325);
DISPLAY INVISIBLE (1025 4325);
FORCEPROP 2 LAST CDS_LIB dev_discrete
J 0
(1025 4175);
PAINT ORANGE (1025 4175);
DISPLAY INVISIBLE (1025 4175);
FORCEPROP 2 LAST BOM_COST ST_SATA
J 0
(925 4325);
DISPLAY 1.361702 (925 4325);
PAINT ORANGE (925 4325);
DISPLAY INVISIBLE (925 4325);
FORCEPROP 2 LAST CDS_LOCATION C2L44
J 1
(1025 4275);
DISPLAY 0.617021 (1025 4275);
PAINT AQUA (1025 4275);
DISPLAY INVISIBLE (1025 4275);
FORCEADD TAP..1
(1450 3650);
FORCEPROP 3 LASTPIN (1400 3650) SIG_NAME SATA6G_PCH_PCIE_UP_SATA_TXP<2>
J 0
(1410 3660);
DISPLAY 0.659574 (1410 3660);
PAINT MONO (1410 3660);
DISPLAY INVISIBLE (1410 3660);
FORCEPROP 1 LASTPIN (1400 3650) BN 2
J 0
(1388 3658);
DISPLAY 0.617021 (1388 3658);
PAINT GREEN (1388 3658);
FORCEPROP 1 LAST PATH I229
J 0
(1448 3650);
DISPLAY 0.872340 (1448 3650);
PAINT GREEN (1448 3650);
DISPLAY INVISIBLE (1448 3650);
FORCEPROP 2 LAST CDS_LIB mstr_standard
J 0
(1450 3650);
PAINT ORANGE (1450 3650);
DISPLAY INVISIBLE (1450 3650);
FORCEPROP 1 LAST BODY_TYPE PLUMBING
J 0
(1450 3700);
DISPLAY 0.872340 (1450 3700);
PAINT GREEN (1450 3700);
DISPLAY INVISIBLE (1450 3700);
FORCEPROP 1 LAST HDL_TAP TRUE
J 0
(1775 3525);
DISPLAY 0.872340 (1775 3525);
PAINT ORANGE (1775 3525);
DISPLAY INVISIBLE (1775 3525);
FORCEADD TAP..1
(1450 3300);
FORCEPROP 3 LASTPIN (1400 3300) SIG_NAME SATA6G_PCH_PCIE_UP_SATA_TXP<3>
J 0
(1410 3310);
DISPLAY 0.659574 (1410 3310);
PAINT MONO (1410 3310);
DISPLAY INVISIBLE (1410 3310);
FORCEPROP 1 LASTPIN (1400 3300) BN 3
J 0
(1388 3308);
DISPLAY 0.617021 (1388 3308);
PAINT GREEN (1388 3308);
FORCEPROP 1 LAST PATH I230
J 0
(1448 3300);
DISPLAY 0.872340 (1448 3300);
PAINT GREEN (1448 3300);
DISPLAY INVISIBLE (1448 3300);
FORCEPROP 2 LAST CDS_LIB mstr_standard
J 0
(1450 3300);
PAINT ORANGE (1450 3300);
DISPLAY INVISIBLE (1450 3300);
FORCEPROP 1 LAST BODY_TYPE PLUMBING
J 0
(1450 3350);
DISPLAY 0.872340 (1450 3350);
PAINT GREEN (1450 3350);
DISPLAY INVISIBLE (1450 3350);
FORCEPROP 1 LAST HDL_TAP TRUE
J 0
(1775 3175);
DISPLAY 0.872340 (1775 3175);
PAINT ORANGE (1775 3175);
DISPLAY INVISIBLE (1775 3175);
FORCEADD TAP..1
(1300 3500);
FORCEPROP 3 LASTPIN (1250 3500) SIG_NAME SATA6G_PCH_PCIE_UP_SATA_TXN<2>
J 0
(1260 3510);
DISPLAY 0.659574 (1260 3510);
PAINT MONO (1260 3510);
DISPLAY INVISIBLE (1260 3510);
FORCEPROP 1 LASTPIN (1250 3500) BN 2
J 0
(1238 3508);
DISPLAY 0.617021 (1238 3508);
PAINT GREEN (1238 3508);
FORCEPROP 1 LAST PATH I231
J 0
(1298 3500);
DISPLAY 0.872340 (1298 3500);
PAINT GREEN (1298 3500);
DISPLAY INVISIBLE (1298 3500);
FORCEPROP 2 LAST CDS_LIB mstr_standard
J 0
(1300 3500);
PAINT ORANGE (1300 3500);
DISPLAY INVISIBLE (1300 3500);
FORCEPROP 1 LAST BODY_TYPE PLUMBING
J 0
(1300 3550);
DISPLAY 0.872340 (1300 3550);
PAINT GREEN (1300 3550);
DISPLAY INVISIBLE (1300 3550);
FORCEPROP 1 LAST HDL_TAP TRUE
J 0
(1625 3375);
DISPLAY 0.872340 (1625 3375);
PAINT ORANGE (1625 3375);
DISPLAY INVISIBLE (1625 3375);
FORCEADD TAP..1
(1300 3075);
FORCEPROP 3 LASTPIN (1250 3075) SIG_NAME SATA6G_PCH_PCIE_UP_SATA_TXN<3>
J 0
(1260 3085);
DISPLAY 0.659574 (1260 3085);
PAINT MONO (1260 3085);
DISPLAY INVISIBLE (1260 3085);
FORCEPROP 1 LASTPIN (1250 3075) BN 3
J 0
(1238 3083);
DISPLAY 0.617021 (1238 3083);
PAINT GREEN (1238 3083);
FORCEPROP 1 LAST PATH I232
J 0
(1298 3075);
DISPLAY 0.872340 (1298 3075);
PAINT GREEN (1298 3075);
DISPLAY INVISIBLE (1298 3075);
FORCEPROP 2 LAST CDS_LIB mstr_standard
J 0
(1300 3075);
PAINT ORANGE (1300 3075);
DISPLAY INVISIBLE (1300 3075);
FORCEPROP 1 LAST BODY_TYPE PLUMBING
J 0
(1300 3125);
DISPLAY 0.872340 (1300 3125);
PAINT GREEN (1300 3125);
DISPLAY INVISIBLE (1300 3125);
FORCEPROP 1 LAST HDL_TAP TRUE
J 0
(1625 2950);
DISPLAY 0.872340 (1625 2950);
PAINT ORANGE (1625 2950);
DISPLAY INVISIBLE (1625 2950);
FORCEADD CAP_A..2
(1000 3500);
FORCEPROP 1 LAST LOCATION C2L42
J 1
(1000 3600);
DISPLAY 0.617021 (1000 3600);
PAINT AQUA (1000 3600);
FORCEPROP 1 LAST VALUE 0.01UF
J 2
(1000 3400);
DISPLAY 0.617021 (1000 3400);
PAINT SKYBLUE (1000 3400);
FORCEPROP 1 LAST TOLERANCE 10%
J 2
(1000 3350);
DISPLAY 0.617021 (1000 3350);
PAINT SKYBLUE (1000 3350);
FORCEPROP 1 LAST PACK_TYPE 0402V
J 1
(1000 3300);
DISPLAY 0.617021 (1000 3300);
PAINT SKYBLUE (1000 3300);
FORCEPROP 1 LAST VOLTAGE 25V
J 0
(1000 3400);
DISPLAY 0.617021 (1000 3400);
PAINT SKYBLUE (1000 3400);
FORCEPROP 1 LAST MATERIAL X7R
J 0
(1000 3350);
DISPLAY 0.617021 (1000 3350);
PAINT SKYBLUE (1000 3350);
FORCEPROP 1 LASTPIN (900 3500) $PN 1
J 0
(890 3515);
DISPLAY 0.617021 (890 3515);
PAINT ORANGE (890 3515);
FORCEPROP 1 LASTPIN (1100 3500) $PN 2
J 0
(1085 3515);
DISPLAY 0.617021 (1085 3515);
PAINT ORANGE (1085 3515);
FORCEPROP 1 LAST PART_NUMBER A36096-045
J 1
(1000 3550);
DISPLAY 0.617021 (1000 3550);
PAINT BLUE (1000 3550);
FORCEPROP 2 LAST ROOM ST_SATA
J 0
(925 3650);
DISPLAY 1.361702 (925 3650);
PAINT ORANGE (925 3650);
DISPLAY INVISIBLE (925 3650);
FORCEPROP 2 LAST CDS_LOCATION C2L42
J 1
(1000 3600);
DISPLAY 0.617021 (1000 3600);
PAINT AQUA (1000 3600);
DISPLAY INVISIBLE (1000 3600);
FORCEPROP 2 LAST BOM_COST ST_SATA
J 0
(925 3650);
DISPLAY 1.361702 (925 3650);
PAINT ORANGE (925 3650);
DISPLAY INVISIBLE (925 3650);
FORCEPROP 2 LAST CDS_LIB dev_discrete
J 0
(1000 3500);
PAINT ORANGE (1000 3500);
DISPLAY INVISIBLE (1000 3500);
FORCEPROP 2 LAST CDS_SEC 1
J 0
(1000 3650);
PAINT ORANGE (1000 3650);
DISPLAY INVISIBLE (1000 3650);
FORCEPROP 2 LAST SEC_TYPE 0402V
J 0
(1000 3750);
DISPLAY 1.021277 (1000 3750);
PAINT ORANGE (1000 3750);
DISPLAY INVISIBLE (1000 3750);
FORCEPROP 2 LAST SEC 1
J 0
(1000 3750);
DISPLAY 0.680851 (1000 3750);
PAINT MONO (1000 3750);
DISPLAY INVISIBLE (1000 3750);
FORCEPROP 1 LAST PATH I233
J 0
(1000 3700);
DISPLAY 0.978723 (1000 3700);
PAINT WHITE (1000 3700);
DISPLAY INVISIBLE (1000 3700);
FORCEADD CAP_A..2
(1025 3075);
FORCEPROP 1 LAST LOCATION C2L22
J 1
(1025 3175);
DISPLAY 0.617021 (1025 3175);
PAINT AQUA (1025 3175);
FORCEPROP 1 LAST PART_NUMBER A36096-045
J 1
(1025 3125);
DISPLAY 0.617021 (1025 3125);
PAINT BLUE (1025 3125);
FORCEPROP 1 LAST VALUE 0.01UF
J 2
(1025 2975);
DISPLAY 0.617021 (1025 2975);
PAINT SKYBLUE (1025 2975);
FORCEPROP 1 LAST TOLERANCE 10%
J 2
(1025 2925);
DISPLAY 0.617021 (1025 2925);
PAINT SKYBLUE (1025 2925);
FORCEPROP 1 LAST PACK_TYPE 0402V
J 1
(1025 2875);
DISPLAY 0.617021 (1025 2875);
PAINT SKYBLUE (1025 2875);
FORCEPROP 1 LAST VOLTAGE 25V
J 0
(1025 2975);
DISPLAY 0.617021 (1025 2975);
PAINT SKYBLUE (1025 2975);
FORCEPROP 1 LAST MATERIAL X7R
J 0
(1025 2925);
DISPLAY 0.617021 (1025 2925);
PAINT SKYBLUE (1025 2925);
FORCEPROP 1 LASTPIN (925 3075) $PN 1
J 0
(915 3090);
DISPLAY 0.617021 (915 3090);
PAINT ORANGE (915 3090);
FORCEPROP 1 LASTPIN (1125 3075) $PN 2
J 0
(1110 3090);
DISPLAY 0.617021 (1110 3090);
PAINT ORANGE (1110 3090);
FORCEPROP 2 LAST ROOM ST_SATA
J 0
(950 3225);
DISPLAY 1.361702 (950 3225);
PAINT ORANGE (950 3225);
DISPLAY INVISIBLE (950 3225);
FORCEPROP 2 LAST CDS_LOCATION C2L22
J 1
(1025 3175);
DISPLAY 0.617021 (1025 3175);
PAINT AQUA (1025 3175);
DISPLAY INVISIBLE (1025 3175);
FORCEPROP 2 LAST BOM_COST ST_SATA
J 0
(950 3225);
DISPLAY 1.361702 (950 3225);
PAINT ORANGE (950 3225);
DISPLAY INVISIBLE (950 3225);
FORCEPROP 2 LAST CDS_LIB dev_discrete
J 0
(1025 3075);
PAINT ORANGE (1025 3075);
DISPLAY INVISIBLE (1025 3075);
FORCEPROP 2 LAST CDS_SEC 1
J 0
(1025 3225);
PAINT ORANGE (1025 3225);
DISPLAY INVISIBLE (1025 3225);
FORCEPROP 2 LAST SEC_TYPE 0402V
J 0
(1025 3325);
DISPLAY 1.021277 (1025 3325);
PAINT ORANGE (1025 3325);
DISPLAY INVISIBLE (1025 3325);
FORCEPROP 2 LAST SEC 1
J 0
(1025 3325);
DISPLAY 0.680851 (1025 3325);
PAINT MONO (1025 3325);
DISPLAY INVISIBLE (1025 3325);
FORCEPROP 1 LAST PATH I234
J 0
(1025 3275);
DISPLAY 0.978723 (1025 3275);
PAINT WHITE (1025 3275);
DISPLAY INVISIBLE (1025 3275);
FORCEADD TAP..1
(1450 2925);
FORCEPROP 3 LASTPIN (1400 2925) SIG_NAME SATA6G_PCH_PCIE_UP_SATA_TXP<4>
J 0
(1410 2935);
DISPLAY 0.659574 (1410 2935);
PAINT MONO (1410 2935);
DISPLAY INVISIBLE (1410 2935);
FORCEPROP 1 LASTPIN (1400 2925) BN 4
J 0
(1388 2933);
DISPLAY 0.617021 (1388 2933);
PAINT GREEN (1388 2933);
FORCEPROP 1 LAST PATH I235
J 0
(1448 2925);
DISPLAY 0.872340 (1448 2925);
PAINT GREEN (1448 2925);
DISPLAY INVISIBLE (1448 2925);
FORCEPROP 2 LAST CDS_LIB mstr_standard
J 0
(1450 2925);
PAINT ORANGE (1450 2925);
DISPLAY INVISIBLE (1450 2925);
FORCEPROP 1 LAST BODY_TYPE PLUMBING
J 0
(1450 2975);
DISPLAY 0.872340 (1450 2975);
PAINT GREEN (1450 2975);
DISPLAY INVISIBLE (1450 2975);
FORCEPROP 1 LAST HDL_TAP TRUE
J 0
(1775 2800);
DISPLAY 0.872340 (1775 2800);
PAINT ORANGE (1775 2800);
DISPLAY INVISIBLE (1775 2800);
FORCEADD TAP..1
(1450 2500);
FORCEPROP 3 LASTPIN (1400 2500) SIG_NAME SATA6G_PCH_PCIE_UP_SATA_TXP<5>
J 0
(1410 2510);
DISPLAY 0.659574 (1410 2510);
PAINT MONO (1410 2510);
DISPLAY INVISIBLE (1410 2510);
FORCEPROP 1 LASTPIN (1400 2500) BN 5
J 0
(1388 2508);
DISPLAY 0.617021 (1388 2508);
PAINT GREEN (1388 2508);
FORCEPROP 1 LAST PATH I236
J 0
(1448 2500);
DISPLAY 0.872340 (1448 2500);
PAINT GREEN (1448 2500);
DISPLAY INVISIBLE (1448 2500);
FORCEPROP 2 LAST CDS_LIB mstr_standard
J 0
(1450 2500);
PAINT ORANGE (1450 2500);
DISPLAY INVISIBLE (1450 2500);
FORCEPROP 1 LAST BODY_TYPE PLUMBING
J 0
(1450 2550);
DISPLAY 0.872340 (1450 2550);
PAINT GREEN (1450 2550);
DISPLAY INVISIBLE (1450 2550);
FORCEPROP 1 LAST HDL_TAP TRUE
J 0
(1775 2375);
DISPLAY 0.872340 (1775 2375);
PAINT ORANGE (1775 2375);
DISPLAY INVISIBLE (1775 2375);
FORCEADD TAP..1
(1300 2725);
FORCEPROP 3 LASTPIN (1250 2725) SIG_NAME SATA6G_PCH_PCIE_UP_SATA_TXN<4>
J 0
(1260 2735);
DISPLAY 0.659574 (1260 2735);
PAINT MONO (1260 2735);
DISPLAY INVISIBLE (1260 2735);
FORCEPROP 1 LASTPIN (1250 2725) BN 4
J 0
(1238 2733);
DISPLAY 0.617021 (1238 2733);
PAINT GREEN (1238 2733);
FORCEPROP 2 LAST CDS_LIB mstr_standard
J 0
(1300 2725);
PAINT ORANGE (1300 2725);
DISPLAY INVISIBLE (1300 2725);
FORCEPROP 1 LAST PATH I237
J 0
(1298 2725);
DISPLAY 0.872340 (1298 2725);
PAINT GREEN (1298 2725);
DISPLAY INVISIBLE (1298 2725);
FORCEPROP 1 LAST BODY_TYPE PLUMBING
J 0
(1300 2775);
DISPLAY 0.872340 (1300 2775);
PAINT GREEN (1300 2775);
DISPLAY INVISIBLE (1300 2775);
FORCEPROP 1 LAST HDL_TAP TRUE
J 0
(1625 2600);
DISPLAY 0.872340 (1625 2600);
PAINT ORANGE (1625 2600);
DISPLAY INVISIBLE (1625 2600);
FORCEADD CAP_A..2
(1025 2725);
FORCEPROP 1 LAST LOCATION C2L37
J 1
(1025 2825);
DISPLAY 0.617021 (1025 2825);
PAINT AQUA (1025 2825);
FORCEPROP 1 LAST PART_NUMBER A36096-045
J 1
(1025 2775);
DISPLAY 0.617021 (1025 2775);
PAINT BLUE (1025 2775);
FORCEPROP 1 LAST VALUE 0.01UF
J 2
(1025 2625);
DISPLAY 0.617021 (1025 2625);
PAINT SKYBLUE (1025 2625);
FORCEPROP 1 LAST TOLERANCE 10%
J 2
(1025 2575);
DISPLAY 0.617021 (1025 2575);
PAINT SKYBLUE (1025 2575);
FORCEPROP 1 LAST PACK_TYPE 0402V
J 1
(1025 2525);
DISPLAY 0.617021 (1025 2525);
PAINT SKYBLUE (1025 2525);
FORCEPROP 1 LAST VOLTAGE 25V
J 0
(1025 2625);
DISPLAY 0.617021 (1025 2625);
PAINT SKYBLUE (1025 2625);
FORCEPROP 1 LAST MATERIAL X7R
J 0
(1025 2575);
DISPLAY 0.617021 (1025 2575);
PAINT SKYBLUE (1025 2575);
FORCEPROP 1 LASTPIN (925 2725) $PN 1
J 0
(915 2740);
DISPLAY 0.617021 (915 2740);
PAINT ORANGE (915 2740);
FORCEPROP 1 LASTPIN (1125 2725) $PN 2
J 0
(1110 2740);
DISPLAY 0.617021 (1110 2740);
PAINT ORANGE (1110 2740);
FORCEPROP 2 LAST ROOM ST_SATA
J 0
(975 2875);
DISPLAY 1.361702 (975 2875);
PAINT ORANGE (975 2875);
DISPLAY INVISIBLE (975 2875);
FORCEPROP 2 LAST CDS_LOCATION C2L37
J 1
(1025 2825);
DISPLAY 0.617021 (1025 2825);
PAINT AQUA (1025 2825);
DISPLAY INVISIBLE (1025 2825);
FORCEPROP 2 LAST BOM_COST ST_SATA
J 0
(975 2875);
DISPLAY 1.361702 (975 2875);
PAINT ORANGE (975 2875);
DISPLAY INVISIBLE (975 2875);
FORCEPROP 2 LAST CDS_LIB dev_discrete
J 0
(1025 2725);
PAINT ORANGE (1025 2725);
DISPLAY INVISIBLE (1025 2725);
FORCEPROP 2 LAST CDS_SEC 1
J 0
(1025 2875);
PAINT ORANGE (1025 2875);
DISPLAY INVISIBLE (1025 2875);
FORCEPROP 2 LAST SEC_TYPE 0402V
J 0
(1025 2975);
DISPLAY 1.021277 (1025 2975);
PAINT ORANGE (1025 2975);
DISPLAY INVISIBLE (1025 2975);
FORCEPROP 2 LAST SEC 1
J 0
(1025 2975);
DISPLAY 0.680851 (1025 2975);
PAINT MONO (1025 2975);
DISPLAY INVISIBLE (1025 2975);
FORCEPROP 1 LAST PATH I238
J 0
(1025 2925);
DISPLAY 0.978723 (1025 2925);
PAINT WHITE (1025 2925);
DISPLAY INVISIBLE (1025 2925);
FORCEADD CAP_A..2
(650 2925);
FORCEPROP 1 LAST LOCATION C2L47
J 1
(650 3025);
DISPLAY 0.617021 (650 3025);
PAINT AQUA (650 3025);
FORCEPROP 1 LAST PART_NUMBER A36096-045
J 1
(650 2975);
DISPLAY 0.617021 (650 2975);
PAINT BLUE (650 2975);
FORCEPROP 1 LAST VALUE 0.01UF
J 2
(650 2825);
DISPLAY 0.617021 (650 2825);
PAINT SKYBLUE (650 2825);
FORCEPROP 1 LAST TOLERANCE 10%
J 2
(650 2775);
DISPLAY 0.617021 (650 2775);
PAINT SKYBLUE (650 2775);
FORCEPROP 1 LAST PACK_TYPE 0402V
J 1
(650 2725);
DISPLAY 0.617021 (650 2725);
PAINT SKYBLUE (650 2725);
FORCEPROP 1 LAST VOLTAGE 25V
J 0
(650 2825);
DISPLAY 0.617021 (650 2825);
PAINT SKYBLUE (650 2825);
FORCEPROP 1 LAST MATERIAL X7R
J 0
(650 2775);
DISPLAY 0.617021 (650 2775);
PAINT SKYBLUE (650 2775);
FORCEPROP 1 LASTPIN (750 2925) $PN 2
J 0
(735 2940);
DISPLAY 0.617021 (735 2940);
PAINT ORANGE (735 2940);
FORCEPROP 1 LASTPIN (550 2925) $PN 1
J 0
(540 2940);
DISPLAY 0.617021 (540 2940);
PAINT ORANGE (540 2940);
FORCEPROP 2 LAST ROOM ST_SATA
J 0
(600 3075);
DISPLAY 1.361702 (600 3075);
PAINT ORANGE (600 3075);
DISPLAY INVISIBLE (600 3075);
FORCEPROP 1 LAST PATH I239
J 0
(650 3125);
DISPLAY 0.978723 (650 3125);
PAINT WHITE (650 3125);
DISPLAY INVISIBLE (650 3125);
FORCEPROP 2 LAST SEC 1
J 0
(650 3175);
DISPLAY 0.680851 (650 3175);
PAINT MONO (650 3175);
DISPLAY INVISIBLE (650 3175);
FORCEPROP 2 LAST SEC_TYPE 0402V
J 0
(650 3175);
DISPLAY 1.021277 (650 3175);
PAINT ORANGE (650 3175);
DISPLAY INVISIBLE (650 3175);
FORCEPROP 2 LAST CDS_SEC 1
J 0
(650 3075);
PAINT ORANGE (650 3075);
DISPLAY INVISIBLE (650 3075);
FORCEPROP 2 LAST CDS_LIB dev_discrete
J 0
(650 2925);
PAINT ORANGE (650 2925);
DISPLAY INVISIBLE (650 2925);
FORCEPROP 2 LAST BOM_COST ST_SATA
J 0
(600 3075);
DISPLAY 1.361702 (600 3075);
PAINT ORANGE (600 3075);
DISPLAY INVISIBLE (600 3075);
FORCEPROP 2 LAST CDS_LOCATION C2L47
J 1
(650 3025);
DISPLAY 0.617021 (650 3025);
PAINT AQUA (650 3025);
DISPLAY INVISIBLE (650 3025);
FORCEADD CAP_A..2
(650 2500);
FORCEPROP 1 LAST LOCATION C2L27
J 1
(650 2600);
DISPLAY 0.617021 (650 2600);
PAINT AQUA (650 2600);
FORCEPROP 1 LAST TOLERANCE 10%
J 2
(650 2350);
DISPLAY 0.617021 (650 2350);
PAINT SKYBLUE (650 2350);
FORCEPROP 1 LAST PACK_TYPE 0402V
J 1
(650 2300);
DISPLAY 0.617021 (650 2300);
PAINT SKYBLUE (650 2300);
FORCEPROP 1 LAST MATERIAL X7R
J 0
(650 2350);
DISPLAY 0.617021 (650 2350);
PAINT SKYBLUE (650 2350);
FORCEPROP 1 LASTPIN (550 2500) $PN 1
J 0
(540 2515);
DISPLAY 0.617021 (540 2515);
PAINT ORANGE (540 2515);
FORCEPROP 1 LAST VOLTAGE 25V
J 0
(650 2400);
DISPLAY 0.617021 (650 2400);
PAINT SKYBLUE (650 2400);
FORCEPROP 1 LAST VALUE 0.01UF
J 2
(650 2400);
DISPLAY 0.617021 (650 2400);
PAINT SKYBLUE (650 2400);
FORCEPROP 1 LAST PART_NUMBER A36096-045
J 1
(650 2550);
DISPLAY 0.617021 (650 2550);
PAINT BLUE (650 2550);
FORCEPROP 1 LASTPIN (750 2500) $PN 2
J 0
(735 2515);
DISPLAY 0.617021 (735 2515);
PAINT ORANGE (735 2515);
FORCEPROP 2 LAST ROOM ST_SATA
J 0
(550 2650);
DISPLAY 1.361702 (550 2650);
PAINT ORANGE (550 2650);
DISPLAY INVISIBLE (550 2650);
FORCEPROP 2 LAST CDS_LOCATION C2L27
J 1
(650 2600);
DISPLAY 0.617021 (650 2600);
PAINT AQUA (650 2600);
DISPLAY INVISIBLE (650 2600);
FORCEPROP 2 LAST BOM_COST ST_SATA
J 0
(550 2650);
DISPLAY 1.361702 (550 2650);
PAINT ORANGE (550 2650);
DISPLAY INVISIBLE (550 2650);
FORCEPROP 2 LAST CDS_LIB dev_discrete
J 0
(650 2500);
PAINT ORANGE (650 2500);
DISPLAY INVISIBLE (650 2500);
FORCEPROP 2 LAST CDS_SEC 1
J 0
(650 2650);
PAINT ORANGE (650 2650);
DISPLAY INVISIBLE (650 2650);
FORCEPROP 2 LAST SEC_TYPE 0402V
J 0
(650 2750);
DISPLAY 1.021277 (650 2750);
PAINT ORANGE (650 2750);
DISPLAY INVISIBLE (650 2750);
FORCEPROP 2 LAST SEC 1
J 0
(650 2750);
DISPLAY 0.680851 (650 2750);
PAINT MONO (650 2750);
DISPLAY INVISIBLE (650 2750);
FORCEPROP 1 LAST PATH I240
J 0
(650 2700);
DISPLAY 0.978723 (650 2700);
PAINT WHITE (650 2700);
DISPLAY INVISIBLE (650 2700);
FORCEADD CAP_A..2
(625 3300);
FORCEPROP 1 LAST LOCATION C2L23
J 1
(625 3400);
DISPLAY 0.617021 (625 3400);
PAINT AQUA (625 3400);
FORCEPROP 1 LAST PART_NUMBER A36096-045
J 1
(625 3350);
DISPLAY 0.617021 (625 3350);
PAINT BLUE (625 3350);
FORCEPROP 1 LAST VALUE 0.01UF
J 2
(625 3200);
DISPLAY 0.617021 (625 3200);
PAINT SKYBLUE (625 3200);
FORCEPROP 1 LAST TOLERANCE 10%
J 2
(625 3150);
DISPLAY 0.617021 (625 3150);
PAINT SKYBLUE (625 3150);
FORCEPROP 1 LAST PACK_TYPE 0402V
J 1
(625 3100);
DISPLAY 0.617021 (625 3100);
PAINT SKYBLUE (625 3100);
FORCEPROP 1 LAST VOLTAGE 25V
J 0
(625 3200);
DISPLAY 0.617021 (625 3200);
PAINT SKYBLUE (625 3200);
FORCEPROP 1 LAST MATERIAL X7R
J 0
(625 3150);
DISPLAY 0.617021 (625 3150);
PAINT SKYBLUE (625 3150);
FORCEPROP 1 LASTPIN (525 3300) $PN 1
J 0
(515 3315);
DISPLAY 0.617021 (515 3315);
PAINT ORANGE (515 3315);
FORCEPROP 1 LASTPIN (725 3300) $PN 2
J 0
(710 3315);
DISPLAY 0.617021 (710 3315);
PAINT ORANGE (710 3315);
FORCEPROP 2 LAST ROOM ST_SATA
J 0
(525 3450);
DISPLAY 1.361702 (525 3450);
PAINT ORANGE (525 3450);
DISPLAY INVISIBLE (525 3450);
FORCEPROP 2 LAST CDS_LOCATION C2L23
J 1
(625 3400);
DISPLAY 0.617021 (625 3400);
PAINT AQUA (625 3400);
DISPLAY INVISIBLE (625 3400);
FORCEPROP 2 LAST BOM_COST ST_SATA
J 0
(525 3450);
DISPLAY 1.361702 (525 3450);
PAINT ORANGE (525 3450);
DISPLAY INVISIBLE (525 3450);
FORCEPROP 2 LAST CDS_LIB dev_discrete
J 0
(625 3300);
PAINT ORANGE (625 3300);
DISPLAY INVISIBLE (625 3300);
FORCEPROP 2 LAST CDS_SEC 1
J 0
(625 3450);
PAINT ORANGE (625 3450);
DISPLAY INVISIBLE (625 3450);
FORCEPROP 2 LAST SEC_TYPE 0402V
J 0
(625 3550);
DISPLAY 1.021277 (625 3550);
PAINT ORANGE (625 3550);
DISPLAY INVISIBLE (625 3550);
FORCEPROP 2 LAST SEC 1
J 0
(625 3550);
DISPLAY 0.680851 (625 3550);
PAINT MONO (625 3550);
DISPLAY INVISIBLE (625 3550);
FORCEPROP 1 LAST PATH I241
J 0
(625 3500);
DISPLAY 0.978723 (625 3500);
PAINT WHITE (625 3500);
DISPLAY INVISIBLE (625 3500);
FORCEADD CAP_A..2
(625 3650);
FORCEPROP 1 LAST LOCATION C2L41
J 1
(625 3750);
DISPLAY 0.617021 (625 3750);
PAINT AQUA (625 3750);
FORCEPROP 1 LAST VALUE 0.01UF
J 2
(625 3550);
DISPLAY 0.617021 (625 3550);
PAINT SKYBLUE (625 3550);
FORCEPROP 1 LAST TOLERANCE 10%
J 2
(625 3500);
DISPLAY 0.617021 (625 3500);
PAINT SKYBLUE (625 3500);
FORCEPROP 1 LAST PACK_TYPE 0402V
J 1
(625 3450);
DISPLAY 0.617021 (625 3450);
PAINT SKYBLUE (625 3450);
FORCEPROP 1 LAST MATERIAL X7R
J 0
(625 3500);
DISPLAY 0.617021 (625 3500);
PAINT SKYBLUE (625 3500);
FORCEPROP 1 LASTPIN (725 3650) $PN 2
J 0
(710 3665);
DISPLAY 0.617021 (710 3665);
PAINT ORANGE (710 3665);
FORCEPROP 1 LASTPIN (525 3650) $PN 1
J 0
(515 3665);
DISPLAY 0.617021 (515 3665);
PAINT ORANGE (515 3665);
FORCEPROP 1 LAST VOLTAGE 25V
J 0
(625 3550);
DISPLAY 0.617021 (625 3550);
PAINT SKYBLUE (625 3550);
FORCEPROP 1 LAST PART_NUMBER A36096-045
J 1
(625 3700);
DISPLAY 0.617021 (625 3700);
PAINT BLUE (625 3700);
FORCEPROP 2 LAST ROOM ST_SATA
J 0
(550 3800);
DISPLAY 1.361702 (550 3800);
PAINT ORANGE (550 3800);
DISPLAY INVISIBLE (550 3800);
FORCEPROP 1 LAST PATH I242
J 0
(625 3850);
DISPLAY 0.978723 (625 3850);
PAINT WHITE (625 3850);
DISPLAY INVISIBLE (625 3850);
FORCEPROP 2 LAST SEC 1
J 0
(625 3900);
DISPLAY 0.680851 (625 3900);
PAINT MONO (625 3900);
DISPLAY INVISIBLE (625 3900);
FORCEPROP 2 LAST SEC_TYPE 0402V
J 0
(625 3900);
DISPLAY 1.021277 (625 3900);
PAINT ORANGE (625 3900);
DISPLAY INVISIBLE (625 3900);
FORCEPROP 2 LAST CDS_SEC 1
J 0
(625 3800);
PAINT ORANGE (625 3800);
DISPLAY INVISIBLE (625 3800);
FORCEPROP 2 LAST CDS_LIB dev_discrete
J 0
(625 3650);
PAINT ORANGE (625 3650);
DISPLAY INVISIBLE (625 3650);
FORCEPROP 2 LAST BOM_COST ST_SATA
J 0
(550 3800);
DISPLAY 1.361702 (550 3800);
PAINT ORANGE (550 3800);
DISPLAY INVISIBLE (550 3800);
FORCEPROP 2 LAST CDS_LOCATION C2L41
J 1
(625 3750);
DISPLAY 0.617021 (625 3750);
PAINT AQUA (625 3750);
DISPLAY INVISIBLE (625 3750);
FORCEADD TAP..1
(1300 2350);
FORCEPROP 3 LASTPIN (1250 2350) SIG_NAME SATA6G_PCH_PCIE_UP_SATA_TXN<5>
J 0
(1260 2360);
DISPLAY 0.659574 (1260 2360);
PAINT MONO (1260 2360);
DISPLAY INVISIBLE (1260 2360);
FORCEPROP 1 LASTPIN (1250 2350) BN 5
J 0
(1238 2358);
DISPLAY 0.617021 (1238 2358);
PAINT GREEN (1238 2358);
FORCEPROP 2 LAST CDS_LIB mstr_standard
J 0
(1300 2350);
PAINT ORANGE (1300 2350);
DISPLAY INVISIBLE (1300 2350);
FORCEPROP 1 LAST PATH I251
J 0
(1298 2350);
DISPLAY 0.872340 (1298 2350);
PAINT GREEN (1298 2350);
DISPLAY INVISIBLE (1298 2350);
FORCEPROP 1 LAST BODY_TYPE PLUMBING
J 0
(1300 2400);
DISPLAY 0.872340 (1300 2400);
PAINT GREEN (1300 2400);
DISPLAY INVISIBLE (1300 2400);
FORCEPROP 1 LAST HDL_TAP TRUE
J 0
(1625 2225);
DISPLAY 0.872340 (1625 2225);
PAINT ORANGE (1625 2225);
DISPLAY INVISIBLE (1625 2225);
FORCEADD TAP..1
(1450 2050);
FORCEPROP 3 LASTPIN (1400 2050) SIG_NAME SATA6G_PCH_PCIE_UP_SATA_TXP<6>
J 0
(1410 2060);
DISPLAY 0.659574 (1410 2060);
PAINT MONO (1410 2060);
DISPLAY INVISIBLE (1410 2060);
FORCEPROP 1 LASTPIN (1400 2050) BN 6
J 0
(1388 2058);
DISPLAY 0.617021 (1388 2058);
PAINT GREEN (1388 2058);
FORCEPROP 2 LAST CDS_LIB mstr_standard
J 0
(1450 2050);
PAINT ORANGE (1450 2050);
DISPLAY INVISIBLE (1450 2050);
FORCEPROP 1 LAST PATH I252
J 0
(1448 2050);
DISPLAY 0.872340 (1448 2050);
PAINT GREEN (1448 2050);
DISPLAY INVISIBLE (1448 2050);
FORCEPROP 1 LAST BODY_TYPE PLUMBING
J 0
(1450 2100);
DISPLAY 0.872340 (1450 2100);
PAINT GREEN (1450 2100);
DISPLAY INVISIBLE (1450 2100);
FORCEPROP 1 LAST HDL_TAP TRUE
J 0
(1775 1925);
DISPLAY 0.872340 (1775 1925);
PAINT ORANGE (1775 1925);
DISPLAY INVISIBLE (1775 1925);
FORCEADD TAP..1
(1450 1700);
FORCEPROP 3 LASTPIN (1400 1700) SIG_NAME SATA6G_PCH_PCIE_UP_SATA_TXP<7>
J 0
(1410 1710);
DISPLAY 0.659574 (1410 1710);
PAINT MONO (1410 1710);
DISPLAY INVISIBLE (1410 1710);
FORCEPROP 1 LASTPIN (1400 1700) BN 7
J 0
(1388 1708);
DISPLAY 0.617021 (1388 1708);
PAINT GREEN (1388 1708);
FORCEPROP 1 LAST PATH I253
J 0
(1448 1700);
DISPLAY 0.872340 (1448 1700);
PAINT GREEN (1448 1700);
DISPLAY INVISIBLE (1448 1700);
FORCEPROP 2 LAST CDS_LIB mstr_standard
J 0
(1450 1700);
PAINT ORANGE (1450 1700);
DISPLAY INVISIBLE (1450 1700);
FORCEPROP 1 LAST BODY_TYPE PLUMBING
J 0
(1450 1750);
DISPLAY 0.872340 (1450 1750);
PAINT GREEN (1450 1750);
DISPLAY INVISIBLE (1450 1750);
FORCEPROP 1 LAST HDL_TAP TRUE
J 0
(1775 1575);
DISPLAY 0.872340 (1775 1575);
PAINT ORANGE (1775 1575);
DISPLAY INVISIBLE (1775 1575);
FORCEADD TAP..1
(1300 1900);
FORCEPROP 3 LASTPIN (1250 1900) SIG_NAME SATA6G_PCH_PCIE_UP_SATA_TXN<6>
J 0
(1260 1910);
DISPLAY 0.659574 (1260 1910);
PAINT MONO (1260 1910);
DISPLAY INVISIBLE (1260 1910);
FORCEPROP 1 LASTPIN (1250 1900) BN 6
J 0
(1238 1908);
DISPLAY 0.617021 (1238 1908);
PAINT GREEN (1238 1908);
FORCEPROP 2 LAST CDS_LIB mstr_standard
J 0
(1300 1900);
PAINT ORANGE (1300 1900);
DISPLAY INVISIBLE (1300 1900);
FORCEPROP 1 LAST PATH I254
J 0
(1298 1900);
DISPLAY 0.872340 (1298 1900);
PAINT GREEN (1298 1900);
DISPLAY INVISIBLE (1298 1900);
FORCEPROP 1 LAST BODY_TYPE PLUMBING
J 0
(1300 1950);
DISPLAY 0.872340 (1300 1950);
PAINT GREEN (1300 1950);
DISPLAY INVISIBLE (1300 1950);
FORCEPROP 1 LAST HDL_TAP TRUE
J 0
(1625 1775);
DISPLAY 0.872340 (1625 1775);
PAINT ORANGE (1625 1775);
DISPLAY INVISIBLE (1625 1775);
FORCEADD CAP_A..2
(1025 2350);
FORCEPROP 1 LAST LOCATION C2L26
J 1
(1025 2450);
DISPLAY 0.617021 (1025 2450);
PAINT AQUA (1025 2450);
FORCEPROP 1 LAST PART_NUMBER A36096-045
J 1
(1025 2400);
DISPLAY 0.617021 (1025 2400);
PAINT BLUE (1025 2400);
FORCEPROP 1 LAST VALUE 0.01UF
J 2
(1025 2250);
DISPLAY 0.617021 (1025 2250);
PAINT SKYBLUE (1025 2250);
FORCEPROP 1 LAST TOLERANCE 10%
J 2
(1025 2200);
DISPLAY 0.617021 (1025 2200);
PAINT SKYBLUE (1025 2200);
FORCEPROP 1 LAST PACK_TYPE 0402V
J 1
(1025 2150);
DISPLAY 0.617021 (1025 2150);
PAINT SKYBLUE (1025 2150);
FORCEPROP 1 LAST VOLTAGE 25V
J 0
(1025 2250);
DISPLAY 0.617021 (1025 2250);
PAINT SKYBLUE (1025 2250);
FORCEPROP 1 LAST MATERIAL X7R
J 0
(1025 2200);
DISPLAY 0.617021 (1025 2200);
PAINT SKYBLUE (1025 2200);
FORCEPROP 1 LASTPIN (925 2350) $PN 1
J 0
(915 2365);
DISPLAY 0.617021 (915 2365);
PAINT ORANGE (915 2365);
FORCEPROP 1 LASTPIN (1125 2350) $PN 2
J 0
(1110 2365);
DISPLAY 0.617021 (1110 2365);
PAINT ORANGE (1110 2365);
FORCEPROP 2 LAST ROOM ST_SATA
J 0
(975 2500);
DISPLAY 1.361702 (975 2500);
PAINT ORANGE (975 2500);
DISPLAY INVISIBLE (975 2500);
FORCEPROP 2 LAST CDS_LOCATION C2L26
J 1
(1025 2450);
DISPLAY 0.617021 (1025 2450);
PAINT AQUA (1025 2450);
DISPLAY INVISIBLE (1025 2450);
FORCEPROP 2 LAST BOM_COST ST_SATA
J 0
(975 2500);
DISPLAY 1.361702 (975 2500);
PAINT ORANGE (975 2500);
DISPLAY INVISIBLE (975 2500);
FORCEPROP 2 LAST CDS_LIB dev_discrete
J 0
(1025 2350);
PAINT ORANGE (1025 2350);
DISPLAY INVISIBLE (1025 2350);
FORCEPROP 2 LAST CDS_SEC 1
J 0
(1025 2500);
PAINT ORANGE (1025 2500);
DISPLAY INVISIBLE (1025 2500);
FORCEPROP 2 LAST SEC_TYPE 0402V
J 0
(1025 2600);
DISPLAY 1.021277 (1025 2600);
PAINT ORANGE (1025 2600);
DISPLAY INVISIBLE (1025 2600);
FORCEPROP 2 LAST SEC 1
J 0
(1025 2600);
DISPLAY 0.680851 (1025 2600);
PAINT MONO (1025 2600);
DISPLAY INVISIBLE (1025 2600);
FORCEPROP 1 LAST PATH I255
J 0
(1025 2550);
DISPLAY 0.978723 (1025 2550);
PAINT WHITE (1025 2550);
DISPLAY INVISIBLE (1025 2550);
FORCEADD CAP_A..2
(1050 1900);
FORCEPROP 1 LAST LOCATION C2L38
J 1
(1050 2000);
DISPLAY 0.617021 (1050 2000);
PAINT AQUA (1050 2000);
FORCEPROP 1 LAST TOLERANCE 10%
J 2
(1050 1750);
DISPLAY 0.617021 (1050 1750);
PAINT SKYBLUE (1050 1750);
FORCEPROP 1 LAST VOLTAGE 25V
J 0
(1050 1800);
DISPLAY 0.617021 (1050 1800);
PAINT SKYBLUE (1050 1800);
FORCEPROP 1 LAST MATERIAL X7R
J 0
(1050 1750);
DISPLAY 0.617021 (1050 1750);
PAINT SKYBLUE (1050 1750);
FORCEPROP 1 LASTPIN (1150 1900) $PN 2
J 0
(1135 1915);
DISPLAY 0.617021 (1135 1915);
PAINT ORANGE (1135 1915);
FORCEPROP 1 LASTPIN (950 1900) $PN 1
J 0
(940 1915);
DISPLAY 0.617021 (940 1915);
PAINT ORANGE (940 1915);
FORCEPROP 1 LAST PART_NUMBER A36096-045
J 1
(1050 1950);
DISPLAY 0.617021 (1050 1950);
PAINT BLUE (1050 1950);
FORCEPROP 1 LAST VALUE 0.01UF
J 2
(1050 1800);
DISPLAY 0.617021 (1050 1800);
PAINT SKYBLUE (1050 1800);
FORCEPROP 1 LAST PACK_TYPE 0402V
J 1
(1050 1700);
DISPLAY 0.617021 (1050 1700);
PAINT SKYBLUE (1050 1700);
FORCEPROP 2 LAST ROOM ST_SATA
J 0
(975 2050);
DISPLAY 1.361702 (975 2050);
PAINT ORANGE (975 2050);
DISPLAY INVISIBLE (975 2050);
FORCEPROP 2 LAST CDS_LOCATION C2L38
J 1
(1050 2000);
DISPLAY 0.617021 (1050 2000);
PAINT AQUA (1050 2000);
DISPLAY INVISIBLE (1050 2000);
FORCEPROP 2 LAST BOM_COST ST_SATA
J 0
(975 2050);
DISPLAY 1.361702 (975 2050);
PAINT ORANGE (975 2050);
DISPLAY INVISIBLE (975 2050);
FORCEPROP 2 LAST CDS_LIB dev_discrete
J 0
(1050 1900);
PAINT ORANGE (1050 1900);
DISPLAY INVISIBLE (1050 1900);
FORCEPROP 2 LAST CDS_SEC 1
J 0
(1050 2050);
PAINT ORANGE (1050 2050);
DISPLAY INVISIBLE (1050 2050);
FORCEPROP 2 LAST SEC_TYPE 0402V
J 0
(1050 2150);
DISPLAY 1.021277 (1050 2150);
PAINT ORANGE (1050 2150);
DISPLAY INVISIBLE (1050 2150);
FORCEPROP 2 LAST SEC 1
J 0
(1050 2150);
DISPLAY 0.680851 (1050 2150);
PAINT MONO (1050 2150);
DISPLAY INVISIBLE (1050 2150);
FORCEPROP 1 LAST PATH I256
J 0
(1050 2100);
DISPLAY 0.978723 (1050 2100);
PAINT WHITE (1050 2100);
DISPLAY INVISIBLE (1050 2100);
FORCEADD CAP_A..2
(650 2050);
FORCEPROP 1 LAST PART_NUMBER A36096-045
J 1
(650 2100);
DISPLAY 0.617021 (650 2100);
PAINT BLUE (650 2100);
FORCEPROP 1 LAST VALUE 0.01UF
J 2
(650 1950);
DISPLAY 0.617021 (650 1950);
PAINT SKYBLUE (650 1950);
FORCEPROP 1 LAST TOLERANCE 10%
J 2
(650 1900);
DISPLAY 0.617021 (650 1900);
PAINT SKYBLUE (650 1900);
FORCEPROP 1 LAST PACK_TYPE 0402V
J 1
(650 1850);
DISPLAY 0.617021 (650 1850);
PAINT SKYBLUE (650 1850);
FORCEPROP 1 LAST VOLTAGE 25V
J 0
(650 1950);
DISPLAY 0.617021 (650 1950);
PAINT SKYBLUE (650 1950);
FORCEPROP 1 LAST MATERIAL X7R
J 0
(650 1900);
DISPLAY 0.617021 (650 1900);
PAINT SKYBLUE (650 1900);
FORCEPROP 1 LASTPIN (750 2050) $PN 2
J 0
(735 2065);
DISPLAY 0.617021 (735 2065);
PAINT ORANGE (735 2065);
FORCEPROP 1 LASTPIN (550 2050) $PN 1
J 0
(540 2065);
DISPLAY 0.617021 (540 2065);
PAINT ORANGE (540 2065);
FORCEPROP 1 LAST LOCATION C2L48
J 1
(650 2150);
DISPLAY 0.617021 (650 2150);
PAINT AQUA (650 2150);
FORCEPROP 2 LAST ROOM ST_SATA
J 0
(550 2200);
DISPLAY 1.361702 (550 2200);
PAINT ORANGE (550 2200);
DISPLAY INVISIBLE (550 2200);
FORCEPROP 2 LAST CDS_LOCATION C2L48
J 1
(650 2150);
DISPLAY 0.617021 (650 2150);
PAINT AQUA (650 2150);
DISPLAY INVISIBLE (650 2150);
FORCEPROP 2 LAST BOM_COST ST_SATA
J 0
(550 2200);
DISPLAY 1.361702 (550 2200);
PAINT ORANGE (550 2200);
DISPLAY INVISIBLE (550 2200);
FORCEPROP 2 LAST CDS_LIB dev_discrete
J 0
(650 2050);
PAINT ORANGE (650 2050);
DISPLAY INVISIBLE (650 2050);
FORCEPROP 2 LAST CDS_SEC 1
J 0
(650 2200);
PAINT ORANGE (650 2200);
DISPLAY INVISIBLE (650 2200);
FORCEPROP 2 LAST SEC_TYPE 0402V
J 0
(650 2300);
DISPLAY 1.021277 (650 2300);
PAINT ORANGE (650 2300);
DISPLAY INVISIBLE (650 2300);
FORCEPROP 2 LAST SEC 1
J 0
(650 2300);
DISPLAY 0.680851 (650 2300);
PAINT MONO (650 2300);
DISPLAY INVISIBLE (650 2300);
FORCEPROP 1 LAST PATH I257
J 0
(650 2250);
DISPLAY 0.978723 (650 2250);
PAINT WHITE (650 2250);
DISPLAY INVISIBLE (650 2250);
FORCEADD CAP_A..2
(650 1700);
FORCEPROP 1 LAST VALUE 0.01UF
J 2
(650 1600);
DISPLAY 0.617021 (650 1600);
PAINT SKYBLUE (650 1600);
FORCEPROP 1 LAST TOLERANCE 10%
J 2
(650 1550);
DISPLAY 0.617021 (650 1550);
PAINT SKYBLUE (650 1550);
FORCEPROP 1 LAST VOLTAGE 25V
J 0
(650 1600);
DISPLAY 0.617021 (650 1600);
PAINT SKYBLUE (650 1600);
FORCEPROP 1 LAST MATERIAL X7R
J 0
(650 1550);
DISPLAY 0.617021 (650 1550);
PAINT SKYBLUE (650 1550);
FORCEPROP 1 LAST LOCATION C2L24
J 1
(650 1800);
DISPLAY 0.617021 (650 1800);
PAINT AQUA (650 1800);
FORCEPROP 1 LAST PACK_TYPE 0402V
J 1
(650 1500);
DISPLAY 0.617021 (650 1500);
PAINT SKYBLUE (650 1500);
FORCEPROP 1 LASTPIN (750 1700) $PN 2
J 0
(735 1715);
DISPLAY 0.617021 (735 1715);
PAINT ORANGE (735 1715);
FORCEPROP 1 LASTPIN (550 1700) $PN 1
J 0
(540 1715);
DISPLAY 0.617021 (540 1715);
PAINT ORANGE (540 1715);
FORCEPROP 1 LAST PART_NUMBER A36096-045
J 1
(650 1750);
DISPLAY 0.617021 (650 1750);
PAINT BLUE (650 1750);
FORCEPROP 2 LAST ROOM ST_SATA
J 0
(550 1850);
DISPLAY 1.361702 (550 1850);
PAINT ORANGE (550 1850);
DISPLAY INVISIBLE (550 1850);
FORCEPROP 1 LAST PATH I258
J 0
(650 1900);
DISPLAY 0.978723 (650 1900);
PAINT WHITE (650 1900);
DISPLAY INVISIBLE (650 1900);
FORCEPROP 2 LAST SEC 1
J 0
(650 1950);
DISPLAY 0.680851 (650 1950);
PAINT MONO (650 1950);
DISPLAY INVISIBLE (650 1950);
FORCEPROP 2 LAST SEC_TYPE 0402V
J 0
(650 1950);
DISPLAY 1.021277 (650 1950);
PAINT ORANGE (650 1950);
DISPLAY INVISIBLE (650 1950);
FORCEPROP 2 LAST CDS_SEC 1
J 0
(650 1850);
PAINT ORANGE (650 1850);
DISPLAY INVISIBLE (650 1850);
FORCEPROP 2 LAST CDS_LIB dev_discrete
J 0
(650 1700);
PAINT ORANGE (650 1700);
DISPLAY INVISIBLE (650 1700);
FORCEPROP 2 LAST BOM_COST ST_SATA
J 0
(550 1850);
DISPLAY 1.361702 (550 1850);
PAINT ORANGE (550 1850);
DISPLAY INVISIBLE (550 1850);
FORCEPROP 2 LAST CDS_LOCATION C2L24
J 1
(650 1800);
DISPLAY 0.617021 (650 1800);
PAINT AQUA (650 1800);
DISPLAY INVISIBLE (650 1800);
FORCEADD CAP_A..2
(1050 1550);
FORCEPROP 1 LAST LOCATION C2L21
J 1
(1050 1650);
DISPLAY 0.617021 (1050 1650);
PAINT AQUA (1050 1650);
FORCEPROP 1 LAST PART_NUMBER A36096-045
J 1
(1050 1600);
DISPLAY 0.617021 (1050 1600);
PAINT BLUE (1050 1600);
FORCEPROP 1 LAST TOLERANCE 10%
J 2
(1050 1400);
DISPLAY 0.617021 (1050 1400);
PAINT SKYBLUE (1050 1400);
FORCEPROP 1 LAST PACK_TYPE 0402V
J 1
(1050 1350);
DISPLAY 0.617021 (1050 1350);
PAINT SKYBLUE (1050 1350);
FORCEPROP 1 LAST VOLTAGE 25V
J 0
(1050 1450);
DISPLAY 0.617021 (1050 1450);
PAINT SKYBLUE (1050 1450);
FORCEPROP 1 LAST MATERIAL X7R
J 0
(1050 1400);
DISPLAY 0.617021 (1050 1400);
PAINT SKYBLUE (1050 1400);
FORCEPROP 1 LASTPIN (1150 1550) $PN 2
J 0
(1135 1565);
DISPLAY 0.617021 (1135 1565);
PAINT ORANGE (1135 1565);
FORCEPROP 1 LASTPIN (950 1550) $PN 1
J 0
(940 1565);
DISPLAY 0.617021 (940 1565);
PAINT ORANGE (940 1565);
FORCEPROP 1 LAST VALUE 0.01UF
J 2
(1050 1450);
DISPLAY 0.617021 (1050 1450);
PAINT SKYBLUE (1050 1450);
FORCEPROP 2 LAST ROOM ST_SATA
J 0
(975 1700);
DISPLAY 1.361702 (975 1700);
PAINT ORANGE (975 1700);
DISPLAY INVISIBLE (975 1700);
FORCEPROP 2 LAST CDS_LOCATION C2L21
J 1
(1050 1650);
DISPLAY 0.617021 (1050 1650);
PAINT AQUA (1050 1650);
DISPLAY INVISIBLE (1050 1650);
FORCEPROP 2 LAST BOM_COST ST_SATA
J 0
(975 1700);
DISPLAY 1.361702 (975 1700);
PAINT ORANGE (975 1700);
DISPLAY INVISIBLE (975 1700);
FORCEPROP 2 LAST CDS_LIB dev_discrete
J 0
(1050 1550);
PAINT ORANGE (1050 1550);
DISPLAY INVISIBLE (1050 1550);
FORCEPROP 2 LAST CDS_SEC 1
J 0
(1050 1700);
PAINT ORANGE (1050 1700);
DISPLAY INVISIBLE (1050 1700);
FORCEPROP 2 LAST SEC_TYPE 0402V
J 0
(1050 1800);
DISPLAY 1.021277 (1050 1800);
PAINT ORANGE (1050 1800);
DISPLAY INVISIBLE (1050 1800);
FORCEPROP 2 LAST SEC 1
J 0
(1050 1800);
DISPLAY 0.680851 (1050 1800);
PAINT MONO (1050 1800);
DISPLAY INVISIBLE (1050 1800);
FORCEPROP 1 LAST PATH I259
J 0
(1050 1750);
DISPLAY 0.978723 (1050 1750);
PAINT WHITE (1050 1750);
DISPLAY INVISIBLE (1050 1750);
FORCEADD P3V3..1
(-4075 2300);
FORCEPROP 3 LASTPIN (-4075 2250) SIG_NAME P3V3\g
J 0
(-4065 2260);
DISPLAY 0.659574 (-4065 2260);
PAINT MONO (-4065 2260);
DISPLAY INVISIBLE (-4065 2260);
FORCEPROP 1 LAST VOLTAGE 3.3V
J 0
(-4120 2257);
DISPLAY 0.340426 (-4120 2257);
PAINT SKYBLUE (-4120 2257);
DISPLAY INVISIBLE (-4120 2257);
FORCEPROP 2 LAST ROOM ST_SATA
J 0
(-3975 2400);
DISPLAY 1.361702 (-3975 2400);
PAINT ORANGE (-3975 2400);
DISPLAY INVISIBLE (-3975 2400);
FORCEPROP 1 LAST PATH I260
J 0
(-4030 2302);
DISPLAY 0.340426 (-4030 2302);
PAINT GREEN (-4030 2302);
DISPLAY INVISIBLE (-4030 2302);
FORCEPROP 2 LAST CDS_LIB mstr_symbols
J 0
(-4075 2300);
PAINT MONO (-4075 2300);
DISPLAY INVISIBLE (-4075 2300);
FORCEPROP 2 LAST BOM_COST ST_SATA
J 0
(-3975 2400);
DISPLAY 1.361702 (-3975 2400);
PAINT ORANGE (-3975 2400);
DISPLAY INVISIBLE (-3975 2400);
FORCEPROP 1 LAST SIZE 1B
J 0
(-4030 2322);
DISPLAY 0.446809 (-4030 2322);
PAINT GREEN (-4030 2322);
DISPLAY INVISIBLE (-4030 2322);
FORCEPROP 1 LAST BODY_TYPE PLUMBING
J 0
(-4120 2257);
DISPLAY 0.446809 (-4120 2257);
PAINT GREEN (-4120 2257);
DISPLAY INVISIBLE (-4120 2257);
FORCEPROP 1 LAST HDL_POWER P3V3
J 0
(-4400 2175);
DISPLAY 1.170213 (-4400 2175);
PAINT GREEN (-4400 2175);
DISPLAY INVISIBLE (-4400 2175);
FORCEADD RES..1
(-3900 2200);
FORCEPROP 1 LAST LOCATION R2L23
J 0
(-3950 2250);
DISPLAY 0.617021 (-3950 2250);
PAINT AQUA (-3950 2250);
FORCEPROP 1 LAST PART_NUMBER G21796-001
J 0
(-3950 2300);
DISPLAY 0.617021 (-3950 2300);
PAINT BLUE (-3950 2300);
FORCEPROP 1 LAST VALUE 2.0K
J 2
(-3925 2100);
DISPLAY 0.617021 (-3925 2100);
PAINT SKYBLUE (-3925 2100);
FORCEPROP 1 LAST TOLERANCE 1%
J 0
(-3900 2100);
DISPLAY 0.617021 (-3900 2100);
PAINT SKYBLUE (-3900 2100);
FORCEPROP 1 LAST PACK_TYPE 0402
J 0
(-3650 2050);
DISPLAY 0.617021 (-3650 2050);
PAINT SKYBLUE (-3650 2050);
FORCEPROP 1 LAST MATERIAL CHIP
J 0
(-3900 2050);
DISPLAY 0.617021 (-3900 2050);
PAINT SKYBLUE (-3900 2050);
FORCEPROP 1 LASTPIN (-3800 2200) $PN 2
J 0
(-3838 2212);
DISPLAY 0.617021 (-3838 2212);
PAINT ORANGE (-3838 2212);
FORCEPROP 1 LASTPIN (-4000 2200) $PN 1
J 0
(-3988 2212);
DISPLAY 0.617021 (-3988 2212);
PAINT ORANGE (-3988 2212);
FORCEPROP 1 LAST WATTAGE 1/16W
J 2
(-3925 2050);
DISPLAY 0.617021 (-3925 2050);
PAINT SKYBLUE (-3925 2050);
FORCEPROP 2 LAST ROOM ST_SATA
J 0
(-3850 2375);
DISPLAY 1.361702 (-3850 2375);
PAINT ORANGE (-3850 2375);
DISPLAY INVISIBLE (-3850 2375);
FORCEPROP 2 LAST SEC_TYPE 0402
J 0
(-3950 2400);
DISPLAY 1.021277 (-3950 2400);
PAINT ORANGE (-3950 2400);
DISPLAY INVISIBLE (-3950 2400);
FORCEPROP 2 LAST CDS_LIB mstr_discrete
J 0
(-3900 2200);
PAINT ORANGE (-3900 2200);
DISPLAY INVISIBLE (-3900 2200);
FORCEPROP 2 LAST BOM_COST ST_SATA
J 0
(-3850 2375);
DISPLAY 1.361702 (-3850 2375);
PAINT ORANGE (-3850 2375);
DISPLAY INVISIBLE (-3850 2375);
FORCEPROP 2 LAST SEC 1
J 0
(-3950 2400);
DISPLAY 0.680851 (-3950 2400);
PAINT MONO (-3950 2400);
DISPLAY INVISIBLE (-3950 2400);
FORCEPROP 2 LAST CDS_LOCATION R2L23
J 0
(-3950 2250);
DISPLAY 0.617021 (-3950 2250);
PAINT AQUA (-3950 2250);
DISPLAY INVISIBLE (-3950 2250);
FORCEPROP 1 LAST PATH I261
J 0
(-3950 2350);
DISPLAY 0.978723 (-3950 2350);
PAINT WHITE (-3950 2350);
DISPLAY INVISIBLE (-3950 2350);
FORCEADD P3V3..1
(-3900 5025);
FORCEPROP 3 LASTPIN (-3900 4975) SIG_NAME P3V3\g
J 0
(-3890 4985);
DISPLAY 0.659574 (-3890 4985);
PAINT MONO (-3890 4985);
DISPLAY INVISIBLE (-3890 4985);
FORCEPROP 1 LAST VOLTAGE 3.3V
J 0
(-3945 4982);
DISPLAY 0.340426 (-3945 4982);
PAINT SKYBLUE (-3945 4982);
DISPLAY INVISIBLE (-3945 4982);
FORCEPROP 2 LAST ROOM ST_SATA
J 0
(-3800 5125);
DISPLAY 1.361702 (-3800 5125);
PAINT ORANGE (-3800 5125);
DISPLAY INVISIBLE (-3800 5125);
FORCEPROP 2 LAST CDS_LIB mstr_symbols
J 0
(-3900 5025);
PAINT ORANGE (-3900 5025);
DISPLAY INVISIBLE (-3900 5025);
FORCEPROP 2 LAST BOM_COST ST_SATA
J 0
(-3800 5125);
DISPLAY 1.361702 (-3800 5125);
PAINT ORANGE (-3800 5125);
DISPLAY INVISIBLE (-3800 5125);
FORCEPROP 1 LAST SIZE 1B
J 0
(-3855 5047);
DISPLAY 0.446809 (-3855 5047);
PAINT GREEN (-3855 5047);
DISPLAY INVISIBLE (-3855 5047);
FORCEPROP 1 LAST PATH I262
J 0
(-3855 5027);
DISPLAY 0.340426 (-3855 5027);
PAINT GREEN (-3855 5027);
DISPLAY INVISIBLE (-3855 5027);
FORCEPROP 1 LAST BODY_TYPE PLUMBING
J 0
(-3945 4982);
DISPLAY 0.446809 (-3945 4982);
PAINT GREEN (-3945 4982);
DISPLAY INVISIBLE (-3945 4982);
FORCEPROP 1 LAST HDL_POWER P3V3
J 0
(-4225 4900);
DISPLAY 1.170213 (-4225 4900);
PAINT GREEN (-4225 4900);
DISPLAY INVISIBLE (-4225 4900);
FORCEADD RES..2
(-3900 4675);
FORCEPROP 1 LAST LOCATION R2L21
J 0
(-3855 4800);
DISPLAY 0.617021 (-3855 4800);
PAINT AQUA (-3855 4800);
FORCEPROP 1 LAST PART_NUMBER G21796-001
J 0
(-3860 4550);
DISPLAY 0.617021 (-3860 4550);
PAINT BLUE (-3860 4550);
FORCEPROP 1 LAST VALUE 2.0K
J 0
(-3855 4750);
DISPLAY 0.617021 (-3855 4750);
PAINT SKYBLUE (-3855 4750);
FORCEPROP 1 LAST TOLERANCE 1%
J 0
(-3855 4700);
DISPLAY 0.617021 (-3855 4700);
PAINT SKYBLUE (-3855 4700);
FORCEPROP 1 LAST PACK_TYPE 0402
J 0
(-3860 4500);
DISPLAY 0.617021 (-3860 4500);
PAINT SKYBLUE (-3860 4500);
FORCEPROP 1 LAST MATERIAL CHIP
J 0
(-3860 4600);
DISPLAY 0.617021 (-3860 4600);
PAINT SKYBLUE (-3860 4600);
FORCEPROP 1 LAST WATTAGE 1/16W
J 0
(-3860 4650);
DISPLAY 0.617021 (-3860 4650);
PAINT SKYBLUE (-3860 4650);
FORCEPROP 1 LASTPIN (-3900 4575) $PN 2
J 0
(-3895 4585);
DISPLAY 0.617021 (-3895 4585);
PAINT ORANGE (-3895 4585);
FORCEPROP 1 LASTPIN (-3900 4775) $PN 1
J 0
(-3895 4737);
DISPLAY 0.617021 (-3895 4737);
PAINT ORANGE (-3895 4737);
FORCEPROP 2 LAST ROOM ST_SATA
J 0
(-3850 4850);
DISPLAY 1.361702 (-3850 4850);
PAINT ORANGE (-3850 4850);
DISPLAY INVISIBLE (-3850 4850);
FORCEPROP 2 LAST SEC_TYPE 0402
J 0
(-3850 4900);
DISPLAY 1.021277 (-3850 4900);
PAINT ORANGE (-3850 4900);
DISPLAY INVISIBLE (-3850 4900);
FORCEPROP 2 LAST CDS_LIB mstr_discrete
J 0
(-3900 4675);
PAINT ORANGE (-3900 4675);
DISPLAY INVISIBLE (-3900 4675);
FORCEPROP 2 LAST BOM_COST ST_SATA
J 0
(-3850 4850);
DISPLAY 1.361702 (-3850 4850);
PAINT ORANGE (-3850 4850);
DISPLAY INVISIBLE (-3850 4850);
FORCEPROP 2 LAST SEC 1
J 0
(-3850 4900);
DISPLAY 0.680851 (-3850 4900);
PAINT MONO (-3850 4900);
DISPLAY INVISIBLE (-3850 4900);
FORCEPROP 2 LAST CDS_LOCATION R2L21
J 0
(-3855 4800);
DISPLAY 0.617021 (-3855 4800);
PAINT AQUA (-3855 4800);
DISPLAY INVISIBLE (-3855 4800);
FORCEPROP 1 LAST PATH I263
J 0
(-3850 4850);
DISPLAY 0.978723 (-3850 4850);
PAINT WHITE (-3850 4850);
DISPLAY INVISIBLE (-3850 4850);
FORCEADD RES..2
(1625 2000);
FORCEPROP 1 LAST LOCATION R2L22
J 0
(1670 2125);
DISPLAY 0.617021 (1670 2125);
PAINT AQUA (1670 2125);
FORCEPROP 1 LAST PART_NUMBER G21796-026
J 0
(1665 1875);
DISPLAY 0.617021 (1665 1875);
PAINT BLUE (1665 1875);
FORCEPROP 1 LAST VALUE 1.00K
J 0
(1670 2075);
DISPLAY 0.617021 (1670 2075);
PAINT SKYBLUE (1670 2075);
FORCEPROP 1 LAST TOLERANCE 1%
J 0
(1670 2025);
DISPLAY 0.617021 (1670 2025);
PAINT SKYBLUE (1670 2025);
FORCEPROP 1 LAST PACK_TYPE 0402
J 0
(1665 1825);
DISPLAY 0.617021 (1665 1825);
PAINT SKYBLUE (1665 1825);
FORCEPROP 1 LAST MATERIAL CHIP
J 0
(1665 1925);
DISPLAY 0.617021 (1665 1925);
PAINT SKYBLUE (1665 1925);
FORCEPROP 1 LAST WATTAGE 1/16W
J 0
(1665 1975);
DISPLAY 0.617021 (1665 1975);
PAINT SKYBLUE (1665 1975);
FORCEPROP 1 LASTPIN (1625 1900) $PN 2
J 0
(1630 1910);
DISPLAY 0.617021 (1630 1910);
PAINT ORANGE (1630 1910);
FORCEPROP 1 LASTPIN (1625 2100) $PN 1
J 0
(1630 2062);
DISPLAY 0.617021 (1630 2062);
PAINT ORANGE (1630 2062);
FORCEPROP 2 LAST ROOM ST_SATA
J 0
(1675 2175);
DISPLAY 1.361702 (1675 2175);
PAINT ORANGE (1675 2175);
DISPLAY INVISIBLE (1675 2175);
FORCEPROP 2 LAST SEC_TYPE 0402
J 0
(1675 2225);
DISPLAY 1.021277 (1675 2225);
PAINT ORANGE (1675 2225);
DISPLAY INVISIBLE (1675 2225);
FORCEPROP 2 LAST BOM_COST ST_SATA
J 0
(1675 2175);
DISPLAY 1.361702 (1675 2175);
PAINT ORANGE (1675 2175);
DISPLAY INVISIBLE (1675 2175);
FORCEPROP 2 LAST CDS_LIB mstr_discrete
J 0
(1625 2000);
PAINT ORANGE (1625 2000);
DISPLAY INVISIBLE (1625 2000);
FORCEPROP 2 LAST SEC 1
J 0
(1675 2225);
DISPLAY 0.680851 (1675 2225);
PAINT MONO (1675 2225);
DISPLAY INVISIBLE (1675 2225);
FORCEPROP 2 LAST CDS_LOCATION R2L22
J 0
(1670 2125);
DISPLAY 0.617021 (1670 2125);
PAINT AQUA (1670 2125);
DISPLAY INVISIBLE (1670 2125);
FORCEPROP 1 LAST PATH I264
J 0
(1675 2175);
DISPLAY 0.978723 (1675 2175);
PAINT WHITE (1675 2175);
DISPLAY INVISIBLE (1675 2175);
FORCEADD GND..1
(1625 1700);
FORCEPROP 3 LASTPIN (1625 1750) SIG_NAME GND\g
J 0
(1635 1760);
DISPLAY 0.659574 (1635 1760);
PAINT MONO (1635 1760);
DISPLAY INVISIBLE (1635 1760);
FORCEPROP 1 LAST VOLTAGE 0.0V
J 0
(1580 1657);
DISPLAY 0.340426 (1580 1657);
PAINT SKYBLUE (1580 1657);
DISPLAY INVISIBLE (1580 1657);
FORCEPROP 2 LAST ROOM ST_SATA
J 0
(1650 1775);
DISPLAY 1.361702 (1650 1775);
PAINT ORANGE (1650 1775);
DISPLAY INVISIBLE (1650 1775);
FORCEPROP 2 LAST BOM_COST ST_SATA
J 0
(1650 1775);
DISPLAY 1.361702 (1650 1775);
PAINT ORANGE (1650 1775);
DISPLAY INVISIBLE (1650 1775);
FORCEPROP 1 LAST SIZE 1B
J 0
(1700 1650);
DISPLAY 1.170213 (1700 1650);
PAINT AQUA (1700 1650);
DISPLAY INVISIBLE (1700 1650);
FORCEPROP 2 LAST CDS_LIB mstr_symbols
J 0
(1625 1700);
PAINT ORANGE (1625 1700);
DISPLAY INVISIBLE (1625 1700);
FORCEPROP 1 LAST PATH I265
J 0
(1700 1700);
DISPLAY 0.872340 (1700 1700);
PAINT AQUA (1700 1700);
DISPLAY INVISIBLE (1700 1700);
FORCEPROP 1 LAST BODY_TYPE PLUMBING
J 0
(1580 1657);
DISPLAY 0.340426 (1580 1657);
PAINT GREEN (1580 1657);
DISPLAY INVISIBLE (1580 1657);
FORCEPROP 1 LAST HDL_POWER GND
J 0
(1625 1850);
DISPLAY 1.170213 (1625 1850);
PAINT GREEN (1625 1850);
DISPLAY INVISIBLE (1625 1850);
FORCEADD RES..2
(1675 3500);
FORCEPROP 1 LAST LOCATION R2L18
J 0
(1720 3625);
DISPLAY 0.617021 (1720 3625);
PAINT AQUA (1720 3625);
FORCEPROP 1 LAST PART_NUMBER G21796-026
J 0
(1715 3375);
DISPLAY 0.617021 (1715 3375);
PAINT BLUE (1715 3375);
FORCEPROP 1 LAST VALUE 1.00K
J 0
(1720 3575);
DISPLAY 0.617021 (1720 3575);
PAINT SKYBLUE (1720 3575);
FORCEPROP 1 LAST TOLERANCE 1%
J 0
(1720 3525);
DISPLAY 0.617021 (1720 3525);
PAINT SKYBLUE (1720 3525);
FORCEPROP 1 LAST PACK_TYPE 0402
J 0
(1715 3325);
DISPLAY 0.617021 (1715 3325);
PAINT SKYBLUE (1715 3325);
FORCEPROP 1 LAST MATERIAL CHIP
J 0
(1715 3425);
DISPLAY 0.617021 (1715 3425);
PAINT SKYBLUE (1715 3425);
FORCEPROP 1 LAST WATTAGE 1/16W
J 0
(1715 3475);
DISPLAY 0.617021 (1715 3475);
PAINT SKYBLUE (1715 3475);
FORCEPROP 1 LASTPIN (1675 3400) $PN 2
J 0
(1680 3410);
DISPLAY 0.617021 (1680 3410);
PAINT ORANGE (1680 3410);
FORCEPROP 1 LASTPIN (1675 3600) $PN 1
J 0
(1680 3562);
DISPLAY 0.617021 (1680 3562);
PAINT ORANGE (1680 3562);
FORCEPROP 2 LAST ROOM ST_SATA
J 0
(1725 3675);
DISPLAY 1.361702 (1725 3675);
PAINT ORANGE (1725 3675);
DISPLAY INVISIBLE (1725 3675);
FORCEPROP 2 LAST SEC_TYPE 0402
J 0
(1725 3725);
DISPLAY 1.021277 (1725 3725);
PAINT ORANGE (1725 3725);
DISPLAY INVISIBLE (1725 3725);
FORCEPROP 2 LAST CDS_LIB mstr_discrete
J 0
(1675 3500);
PAINT ORANGE (1675 3500);
DISPLAY INVISIBLE (1675 3500);
FORCEPROP 2 LAST BOM_COST ST_SATA
J 0
(1725 3675);
DISPLAY 1.361702 (1725 3675);
PAINT ORANGE (1725 3675);
DISPLAY INVISIBLE (1725 3675);
FORCEPROP 2 LAST SEC 1
J 0
(1725 3725);
DISPLAY 0.680851 (1725 3725);
PAINT MONO (1725 3725);
DISPLAY INVISIBLE (1725 3725);
FORCEPROP 2 LAST CDS_LOCATION R2L18
J 0
(1720 3625);
DISPLAY 0.617021 (1720 3625);
PAINT AQUA (1720 3625);
DISPLAY INVISIBLE (1720 3625);
FORCEPROP 1 LAST PATH I266
J 0
(1725 3675);
DISPLAY 0.978723 (1725 3675);
PAINT WHITE (1725 3675);
DISPLAY INVISIBLE (1725 3675);
FORCEADD GND..1
(1675 3275);
FORCEPROP 3 LASTPIN (1675 3325) SIG_NAME GND\g
J 0
(1685 3335);
DISPLAY 0.659574 (1685 3335);
PAINT MONO (1685 3335);
DISPLAY INVISIBLE (1685 3335);
FORCEPROP 1 LAST VOLTAGE 0.0V
J 0
(1630 3232);
DISPLAY 0.340426 (1630 3232);
PAINT SKYBLUE (1630 3232);
DISPLAY INVISIBLE (1630 3232);
FORCEPROP 2 LAST ROOM ST_SATA
J 0
(1700 3350);
DISPLAY 1.361702 (1700 3350);
PAINT ORANGE (1700 3350);
DISPLAY INVISIBLE (1700 3350);
FORCEPROP 1 LAST PATH I267
J 0
(1750 3275);
DISPLAY 0.872340 (1750 3275);
PAINT AQUA (1750 3275);
DISPLAY INVISIBLE (1750 3275);
FORCEPROP 2 LAST CDS_LIB mstr_symbols
J 0
(1675 3275);
PAINT ORANGE (1675 3275);
DISPLAY INVISIBLE (1675 3275);
FORCEPROP 2 LAST BOM_COST ST_SATA
J 0
(1700 3350);
DISPLAY 1.361702 (1700 3350);
PAINT ORANGE (1700 3350);
DISPLAY INVISIBLE (1700 3350);
FORCEPROP 1 LAST SIZE 1B
J 0
(1750 3225);
DISPLAY 1.170213 (1750 3225);
PAINT AQUA (1750 3225);
DISPLAY INVISIBLE (1750 3225);
FORCEPROP 1 LAST BODY_TYPE PLUMBING
J 0
(1630 3232);
DISPLAY 0.340426 (1630 3232);
PAINT GREEN (1630 3232);
DISPLAY INVISIBLE (1630 3232);
FORCEPROP 1 LAST HDL_POWER GND
J 0
(1675 3425);
DISPLAY 1.170213 (1675 3425);
PAINT GREEN (1675 3425);
DISPLAY INVISIBLE (1675 3425);
FORCEADD OFFPAGE..1
(-3575 3800);
FORCEPROP 2 LAST $XR0 178 
J 0
(-3827 3800);
DISPLAY 0.638298 (-3827 3800);
PAINT MONO (-3827 3800);
FORCEPROP 2 LAST CDS_LIB mstr_standard
J 0
(-3575 3800);
PAINT MONO (-3575 3800);
DISPLAY INVISIBLE (-3575 3800);
FORCEPROP 2 LAST PATH I268
J 0
(-3525 3875);
DISPLAY 1.021277 (-3525 3875);
PAINT ORANGE (-3525 3875);
DISPLAY INVISIBLE (-3525 3875);
FORCEPROP 1 LAST OFFPAGE TRUE
J 0
(-3250 3675);
DISPLAY 0.872340 (-3250 3675);
PAINT GREEN (-3250 3675);
DISPLAY INVISIBLE (-3250 3675);
FORCEPROP 1 LAST COMMENT_BODY TRUE
J 0
(-3450 3700);
DISPLAY 0.872340 (-3450 3700);
PAINT GREEN (-3450 3700);
DISPLAY INVISIBLE (-3450 3700);
FORCEADD OFFPAGE..4
(0 3900);
FORCEPROP 2 LAST $XR0 178 
J 0
(186 3900);
DISPLAY 0.638298 (186 3900);
PAINT MONO (186 3900);
FORCEPROP 2 LAST CDS_LIB mstr_standard
J 0
(0 3900);
PAINT MONO (0 3900);
DISPLAY INVISIBLE (0 3900);
FORCEPROP 2 LAST PATH I269
J 0
(175 3975);
DISPLAY 1.021277 (175 3975);
PAINT ORANGE (175 3975);
DISPLAY INVISIBLE (175 3975);
FORCEPROP 1 LAST OFFPAGE TRUE
J 0
(325 3775);
DISPLAY 0.872340 (325 3775);
PAINT GREEN (325 3775);
DISPLAY INVISIBLE (325 3775);
FORCEPROP 1 LAST COMMENT_BODY TRUE
J 0
(-25 3800);
DISPLAY 0.872340 (-25 3800);
PAINT GREEN (-25 3800);
DISPLAY INVISIBLE (-25 3800);
FORCEADD OFFPAGE..4
(0 3850);
FORCEPROP 2 LAST $XR0 178 
J 0
(186 3850);
DISPLAY 0.638298 (186 3850);
PAINT MONO (186 3850);
FORCEPROP 2 LAST CDS_LIB mstr_standard
J 0
(0 3850);
PAINT MONO (0 3850);
DISPLAY INVISIBLE (0 3850);
FORCEPROP 2 LAST PATH I270
J 0
(175 3925);
DISPLAY 1.021277 (175 3925);
PAINT ORANGE (175 3925);
DISPLAY INVISIBLE (175 3925);
FORCEPROP 1 LAST OFFPAGE TRUE
J 0
(325 3725);
DISPLAY 0.872340 (325 3725);
PAINT GREEN (325 3725);
DISPLAY INVISIBLE (325 3725);
FORCEPROP 1 LAST COMMENT_BODY TRUE
J 0
(-25 3750);
DISPLAY 0.872340 (-25 3750);
PAINT GREEN (-25 3750);
DISPLAY INVISIBLE (-25 3750);
FORCEADD TAP..6
(-5250 4050);
FORCEPROP 3 LASTPIN (-5200 4050) SIG_NAME SATA6G_PCH_PCIE_UP_SATA_RXN<1>
J 0
(-5190 4060);
DISPLAY 0.659574 (-5190 4060);
PAINT MONO (-5190 4060);
DISPLAY INVISIBLE (-5190 4060);
FORCEPROP 1 LASTPIN (-5200 4050) BN 1
J 0
(-5252 4058);
DISPLAY 0.617021 (-5252 4058);
PAINT GREEN (-5252 4058);
FORCEPROP 1 LAST PATH I271
J 0
(-5252 4050);
DISPLAY 0.872340 (-5252 4050);
PAINT GREEN (-5252 4050);
DISPLAY INVISIBLE (-5252 4050);
FORCEPROP 2 LAST CDS_LIB mstr_standard
J 0
(-5250 4050);
PAINT ORANGE (-5250 4050);
DISPLAY INVISIBLE (-5250 4050);
FORCEPROP 1 LAST BODY_TYPE PLUMBING
J 0
(-5250 4000);
DISPLAY 0.872340 (-5250 4000);
PAINT GREEN (-5250 4000);
DISPLAY INVISIBLE (-5250 4000);
FORCEPROP 1 LAST HDL_TAP TRUE
J 0
(-4925 3925);
DISPLAY 0.872340 (-4925 3925);
PAINT ORANGE (-4925 3925);
DISPLAY INVISIBLE (-4925 3925);
FORCEADD CAD_NOTE..1
(600 4975);
FORCEPROP 0 LAST L1 PLACE CAPS CLOSE TO PCH
J 0
(450 4850);
DISPLAY 0.829787 (450 4850);
PAINT WHITE (450 4850);
FORCEPROP 2 LAST ROOM ST_SATA
J 0
(450 4900);
DISPLAY 1.361702 (450 4900);
PAINT ORANGE (450 4900);
DISPLAY INVISIBLE (450 4900);
FORCEPROP 2 LAST BOM_COST ST_SATA
J 0
(450 4900);
DISPLAY 1.361702 (450 4900);
PAINT ORANGE (450 4900);
DISPLAY INVISIBLE (450 4900);
FORCEPROP 2 LAST CDS_LIB mstr_symbols
J 0
(600 4975);
PAINT ORANGE (600 4975);
DISPLAY INVISIBLE (600 4975);
FORCEPROP 1 LAST COMMENT_BODY TRUE
J 0
(625 5075);
DISPLAY 1.319149 (625 5075);
PAINT ORANGE (625 5075);
DISPLAY INVISIBLE (625 5075);
FORCEADD CAD_NOTE..1
(-4950 4900);
FORCEPROP 0 LAST L1 PLACE COMPONENTS CLOSE TO CONNECTOR
J 0
(-5100 4775);
DISPLAY 0.829787 (-5100 4775);
PAINT WHITE (-5100 4775);
FORCEPROP 2 LAST ROOM ST_SATA
J 0
(-5100 4800);
DISPLAY 1.361702 (-5100 4800);
PAINT ORANGE (-5100 4800);
DISPLAY INVISIBLE (-5100 4800);
FORCEPROP 2 LAST BOM_COST ST_SATA
J 0
(-5100 4800);
DISPLAY 1.361702 (-5100 4800);
PAINT ORANGE (-5100 4800);
DISPLAY INVISIBLE (-5100 4800);
FORCEPROP 2 LAST CDS_LIB mstr_symbols
J 0
(-4950 4900);
PAINT ORANGE (-4950 4900);
DISPLAY INVISIBLE (-4950 4900);
FORCEPROP 1 LAST COMMENT_BODY TRUE
J 0
(-4925 5000);
DISPLAY 1.319149 (-4925 5000);
PAINT ORANGE (-4925 5000);
DISPLAY INVISIBLE (-4925 5000);
FORCEADD CAD_NOTE..1
(-4950 1175);
FORCEPROP 0 LAST L1 PLACE COMPONENTS CLOSE TO CONNECTOR
J 0
(-5100 1050);
DISPLAY 0.829787 (-5100 1050);
PAINT WHITE (-5100 1050);
FORCEPROP 2 LAST ROOM ST_SATA
J 0
(-5100 1075);
DISPLAY 1.361702 (-5100 1075);
PAINT ORANGE (-5100 1075);
DISPLAY INVISIBLE (-5100 1075);
FORCEPROP 2 LAST CDS_LIB mstr_symbols
J 0
(-4950 1175);
PAINT ORANGE (-4950 1175);
DISPLAY INVISIBLE (-4950 1175);
FORCEPROP 2 LAST BOM_COST ST_SATA
J 0
(-5100 1075);
DISPLAY 1.361702 (-5100 1075);
PAINT ORANGE (-5100 1075);
DISPLAY INVISIBLE (-5100 1075);
FORCEPROP 1 LAST COMMENT_BODY TRUE
J 0
(-4925 1275);
DISPLAY 1.319149 (-4925 1275);
PAINT ORANGE (-4925 1275);
DISPLAY INVISIBLE (-4925 1275);
FORCEADD INTEL_CORP_BPAGE..1
(2125 525);
FORCEPROP 1 LAST CDS_CON_LAST_MODIFIED Fri Jun 16 17:49:04 2017
J 0
(700 850);
PAINT ORANGE (700 850);
DISPLAY INVISIBLE (700 850);
FORCEPROP 1 LAST CUSTOM_TXT_CDS <CURRENT_DESIGN_SHEET> OF <TOTAL_DESIGN_SHEETS>
J 0
(1625 550);
PAINT ORANGE (1625 550);
FORCEPROP 1 LAST CUSTOM_TXT_CDS <CON_LAST_MODIFIED>
J 0
(-1875 625);
PAINT ORANGE (-1875 625);
FORCEPROP 2 LAST CUSTOM_TXT_CDS <XR_PAGE_TITLE>
J 0
(-5765 5775);
DISPLAY 0.638298 (-5765 5775);
PAINT PINK (-5765 5775);
DISPLAY INVISIBLE (-5765 5775);
FORCEPROP 1 LAST SCH_TITLE MINI_SAS (1/2)
J 0
(-5825 575);
DISPLAY 1.212766 (-5825 575);
PAINT ORANGE (-5825 575);
FORCEPROP 2 LAST CDS_LIB mstr_symbols
J 0
(2125 525);
PAINT MONO (2125 525);
DISPLAY INVISIBLE (2125 525);
FORCEPROP 2 LAST PAGE_BORDER TRUE
J 0
(-5765 5775);
DISPLAY 0.638298 (-5765 5775);
PAINT PINK (-5765 5775);
DISPLAY INVISIBLE (-5765 5775);
FORCEPROP 1 LAST COMMENT_BODY TRUE
J 0
(2137 537);
DISPLAY 0.468085 (2137 537);
PAINT GREEN (2137 537);
DISPLAY INVISIBLE (2137 537);
FORCEPROP 2 LAST CDS_XR_PAGE_TITLE CR-173 : @BASEBOARD_FAB2_LIB.BASEBOARD_FAB2(SCH_1):PAGE173
J 0
(-5765 5775);
DISPLAY 0.638298 (-5765 5775);
PAINT PINK (-5765 5775);
DISPLAY INVISIBLE (-5765 5775);
FORCEADD CAD_NOTE..1
(525 1225);
FORCEPROP 0 LAST L1 PLACE CAPS CLOSE TO PCH
J 0
(375 1100);
DISPLAY 0.829787 (375 1100);
PAINT WHITE (375 1100);
FORCEPROP 2 LAST BOM_COST ST_SATA
J 0
(375 1150);
DISPLAY 1.361702 (375 1150);
PAINT ORANGE (375 1150);
DISPLAY INVISIBLE (375 1150);
FORCEPROP 2 LAST CDS_LIB mstr_symbols
J 0
(525 1225);
PAINT ORANGE (525 1225);
DISPLAY INVISIBLE (525 1225);
FORCEPROP 2 LAST ROOM ST_SATA
J 0
(375 1150);
DISPLAY 1.361702 (375 1150);
PAINT ORANGE (375 1150);
DISPLAY INVISIBLE (375 1150);
FORCEPROP 1 LAST COMMENT_BODY TRUE
J 0
(550 1325);
DISPLAY 1.319149 (550 1325);
PAINT ORANGE (550 1325);
DISPLAY INVISIBLE (550 1325);
FORCEADD DESIGN_NOTE..1
(-2175 5175);
FORCEPROP 0 LAST L1 MINI-SAS CONN SATA
J 0
(-2300 5050);
DISPLAY 0.829787 (-2300 5050);
PAINT WHITE (-2300 5050);
FORCEPROP 2 LAST ROOM ST_SATA
J 0
(-2300 5000);
DISPLAY 1.361702 (-2300 5000);
PAINT ORANGE (-2300 5000);
DISPLAY INVISIBLE (-2300 5000);
FORCEPROP 2 LAST CDS_LIB mstr_symbols
J 0
(-2175 5175);
PAINT MONO (-2175 5175);
DISPLAY INVISIBLE (-2175 5175);
FORCEPROP 2 LAST BOM_COST ST_SATA
J 0
(-2300 5000);
DISPLAY 1.361702 (-2300 5000);
PAINT ORANGE (-2300 5000);
DISPLAY INVISIBLE (-2300 5000);
FORCEPROP 1 LAST COMMENT_BODY TRUE
J 0
(-2150 5275);
DISPLAY 1.319149 (-2150 5275);
PAINT ORANGE (-2150 5275);
DISPLAY INVISIBLE (-2150 5275);
WIRE 16 -1 (-1150 1650)(-1150 1475);
WIRE 16 -1 (-1150 1900)(-1150 1650);
WIRE 16 -1 (-1325 1650)(-1150 1650);
WIRE 16 -1 (-1150 1900)(-1150 2150);
WIRE 16 -1 (-1325 1900)(-1150 1900);
WIRE 16 -1 (-1150 2150)(-1150 2300);
WIRE 16 -1 (-1325 2150)(-1150 2150);
WIRE 16 -1 (-1150 2300)(-1150 2500);
WIRE 16 -1 (-1325 2300)(-1150 2300);
WIRE 16 -1 (-1150 2500)(-1150 2750);
WIRE 16 -1 (-1325 2500)(-1150 2500);
WIRE 16 -1 (-1150 3000)(-1150 2750);
WIRE 16 -1 (-1325 2750)(-1150 2750);
WIRE 16 -1 (-1150 3150)(-1150 3000);
WIRE 16 -1 (-1325 3000)(-1150 3000);
WIRE 16 -1 (-1150 3400)(-1150 3150);
WIRE 16 -1 (-1325 3150)(-1150 3150);
WIRE 16 -1 (-1150 3400)(-1150 3650);
WIRE 16 -1 (-1325 3400)(-1150 3400);
WIRE 16 -1 (-1150 3650)(-1150 3800);
WIRE 16 -1 (-1325 3650)(-1150 3650);
WIRE 16 -1 (-1150 3800)(-1150 4000);
WIRE 16 -1 (-1325 3800)(-1150 3800);
WIRE 16 -1 (-1150 4000)(-1150 4250);
WIRE 16 -1 (-1325 4000)(-1150 4000);
WIRE 16 -1 (-1150 4500)(-1150 4250);
WIRE 16 -1 (-1325 4250)(-1150 4250);
WIRE 16 -1 (-1325 4500)(-1150 4500);
WIRE 16 -1 (-2925 1650)(-2925 1500);
WIRE 16 -1 (-2925 1650)(-2925 1900);
WIRE 16 -1 (-2725 1650)(-2925 1650);
WIRE 16 -1 (-2925 1900)(-2925 2150);
WIRE 16 -1 (-2725 1900)(-2925 1900);
WIRE 16 -1 (-2925 2150)(-2925 2350);
WIRE 16 -1 (-2725 2150)(-2925 2150);
WIRE 16 -1 (-2925 2350)(-2925 2500);
WIRE 16 -1 (-2725 2350)(-2925 2350);
WIRE 16 -1 (-2925 2500)(-2925 2750);
WIRE 16 -1 (-2725 2500)(-2925 2500);
WIRE 16 -1 (-2925 3000)(-2925 2750);
WIRE 16 -1 (-2725 2750)(-2925 2750);
WIRE 16 -1 (-2925 3150)(-2925 3000);
WIRE 16 -1 (-2725 3000)(-2925 3000);
WIRE 16 -1 (-2925 3150)(-2925 3400);
WIRE 16 -1 (-2925 3150)(-2725 3150);
WIRE 16 -1 (-2925 3400)(-2925 3650);
WIRE 16 -1 (-2925 3400)(-2725 3400);
WIRE 16 -1 (-2925 3650)(-2925 3850);
WIRE 16 -1 (-2925 3650)(-2725 3650);
WIRE 16 -1 (-2925 3850)(-2925 4000);
WIRE 16 -1 (-2925 3850)(-2725 3850);
WIRE 16 -1 (-2925 4000)(-2925 4250);
WIRE 16 -1 (-2925 4000)(-2725 4000);
WIRE 16 -1 (-2925 4500)(-2925 4250);
WIRE 16 -1 (-2925 4250)(-2725 4250);
WIRE 16 -1 (-2725 4500)(-2925 4500);
WIRE 16 -1 (-4075 2250)(-4075 2200);
WIRE 16 -1 (-4000 2200)(-4075 2200);
WIRE 16 -1 (-3900 4775)(-3900 4975);
WIRE 16 -1 (1625 1900)(1625 1750);
WIRE 16 -1 (1675 3400)(1675 3325);
WIRE 17 -1 (1500 2075)(1500 1725);
WIRE 17 -1 (1500 2075)(1500 2525);
WIRE 17 -1 (1500 2950)(1500 2525);
WIRE 17 -1 (1500 2950)(1500 3325);
WIRE 17 -1 (75 5225)(1500 5225);
FORCEPROP 2 LAST SIG_NAME SATA6G_PCH_PCIE_UP_SATA_TXP<7:0>
J 0
(140 5235);
DISPLAY 0.617021 (140 5235);
PAINT ORANGE (140 5235);
WIRE 17 -1 (1500 3675)(1500 3325);
WIRE 17 -1 (1500 3675)(1500 4350);
WIRE 17 -1 (1500 4700)(1500 5225);
WIRE 17 -1 (1500 4700)(1500 4350);
WIRE 17 -1 (-5300 1875)(-5300 1525);
WIRE 17 -1 (-5300 2425)(-5300 1875);
WIRE 17 -1 (-5300 2775)(-5300 2425);
WIRE 17 -1 (-5300 5150)(-4350 5150);
FORCEPROP 2 LAST SIG_NAME SATA6G_PCH_PCIE_UP_SATA_RXN<7:0>
J 0
(-5110 5160);
DISPLAY 0.617021 (-5110 5160);
PAINT ORANGE (-5110 5160);
WIRE 17 -1 (-5300 4425)(-5300 5150);
WIRE 17 -1 (-5300 2775)(-5300 3225);
WIRE 17 -1 (-5300 3575)(-5300 3225);
WIRE 17 -1 (-5300 4425)(-5300 4075);
WIRE 17 -1 (-5300 4075)(-5300 3575);
WIRE 17 -1 (-4350 5300)(-5450 5300);
FORCEPROP 2 LAST SIG_NAME SATA6G_PCH_PCIE_UP_SATA_RXP<7:0>
J 0
(-5085 5310);
DISPLAY 0.617021 (-5085 5310);
PAINT ORANGE (-5085 5310);
WIRE 17 -1 (-5450 4575)(-5450 5300);
WIRE 17 -1 (-5450 4575)(-5450 4225);
WIRE 17 -1 (-5450 2075)(-5450 1725);
WIRE 17 -1 (-5450 2575)(-5450 2075);
WIRE 17 -1 (-5450 4225)(-5450 3725);
WIRE 17 -1 (-5450 3725)(-5450 3375);
WIRE 17 -1 (-5450 2925)(-5450 2575);
WIRE 17 -1 (-5450 2925)(-5450 3375);
WIRE 17 -1 (1350 5075)(75 5075);
FORCEPROP 2 LAST SIG_NAME SATA6G_PCH_PCIE_UP_SATA_TXN<7:0>
J 0
(140 5085);
DISPLAY 0.617021 (140 5085);
PAINT ORANGE (140 5085);
WIRE 17 -1 (1350 4550)(1350 5075);
WIRE 17 -1 (1350 4550)(1350 4200);
WIRE 17 -1 (1350 4200)(1350 3525);
WIRE 17 -1 (1350 3525)(1350 3100);
WIRE 17 -1 (1350 2750)(1350 3100);
WIRE 17 -1 (1350 2750)(1350 2375);
WIRE 17 -1 (1350 2375)(1350 1925);
WIRE 17 -1 (1350 1925)(1350 1575);
WIRE 16 -1 (-1325 2925)(-1325 2900);
WIRE 16 -1 (-1325 2925)(550 2925);
FORCEPROP 0 LAST SIG_NAME SATA6G_P4_TX_C_DP
J 0
(-1085 2935);
DISPLAY 0.617021 (-1085 2935);
PAINT ORANGE (-1085 2935);
FORCEPROP 2 LASTPROP $XRERR UNIQUE?
J 0
(-1325 2935);
DISPLAY 0.638298 (-1325 2935);
PAINT MONO (-1325 2935);
DISPLAY INVISIBLE (-1325 2935);
WIRE 16 -1 (-1325 1750)(-525 1750);
FORCEPROP 2 LAST SIG_NAME SATA6G_P7_TX_C_DN
J 0
(-1085 1760);
DISPLAY 0.617021 (-1085 1760);
PAINT ORANGE (-1085 1760);
FORCEPROP 2 LASTPROP $XRERR UNIQUE?
J 0
(-1325 1760);
DISPLAY 0.638298 (-1325 1760);
PAINT MONO (-1325 1760);
DISPLAY INVISIBLE (-1325 1760);
WIRE 16 -1 (-525 1550)(-525 1750);
WIRE 16 -1 (-525 1550)(950 1550);
WIRE 16 -1 (-2725 1800)(-4000 1800);
FORCEPROP 2 LAST SIG_NAME SATA6G_P7_RX_C_DP
J 0
(-3500 1810);
DISPLAY 0.617021 (-3500 1810);
PAINT ORANGE (-3500 1810);
FORCEPROP 2 LASTPROP $XRERR UNIQUE?
J 0
(-3740 1810);
DISPLAY 0.638298 (-3740 1810);
PAINT MONO (-3740 1810);
DISPLAY INVISIBLE (-3740 1810);
WIRE 16 -1 (-4000 1700)(-4000 1800);
WIRE 16 -1 (-4475 1700)(-4000 1700);
WIRE 16 -1 (1625 2250)(1625 2100);
WIRE 16 -1 (-1325 2250)(1625 2250);
FORCEPROP 2 LAST SIG_NAME PD_SATA1_CONTROLLER_TYPE_R
J 0
(-1085 2260);
DISPLAY 0.617021 (-1085 2260);
PAINT ORANGE (-1085 2260);
FORCEPROP 2 LASTPROP $XRERR UNIQUE?
J 0
(-1325 2260);
DISPLAY 0.638298 (-1325 2260);
PAINT MONO (-1325 2260);
DISPLAY INVISIBLE (-1325 2260);
WIRE 16 -1 (-4750 4050)(-4225 4050);
FORCEPROP 2 LAST SIG_NAME SATA6G_P1_RX_C_DN
J 0
(-3500 4110);
DISPLAY 0.617021 (-3500 4110);
PAINT ORANGE (-3500 4110);
FORCEPROP 2 LASTPROP $XRERR UNIQUE?
J 0
(-3740 4110);
DISPLAY 0.638298 (-3740 4110);
PAINT MONO (-3740 4110);
DISPLAY INVISIBLE (-3740 4110);
WIRE 16 -1 (-4225 4050)(-4225 4100);
WIRE 16 -1 (-4225 4100)(-2725 4100);
WIRE 16 -1 (1125 4525)(1250 4525);
WIRE 16 -1 (1125 4175)(1250 4175);
WIRE 16 -1 (750 4675)(1400 4675);
WIRE 16 -1 (1100 3500)(1250 3500);
WIRE 16 -1 (1125 3075)(1250 3075);
WIRE 16 -1 (1125 2725)(1250 2725);
WIRE 16 -1 (1125 2350)(1250 2350);
WIRE 16 -1 (725 3300)(1400 3300);
WIRE 16 -1 (750 2925)(1400 2925);
WIRE 16 -1 (750 2050)(1400 2050);
WIRE 16 -1 (1150 1900)(1250 1900);
WIRE 16 -1 (1150 1550)(1250 1550);
WIRE 16 -1 (-1325 3500)(900 3500);
FORCEPROP 2 LAST SIG_NAME SATA6G_P2_TX_C_DN
J 0
(-1085 3510);
DISPLAY 0.617021 (-1085 3510);
PAINT ORANGE (-1085 3510);
FORCEPROP 2 LASTPROP $XRERR UNIQUE?
J 0
(-1325 3510);
DISPLAY 0.638298 (-1325 3510);
PAINT MONO (-1325 3510);
DISPLAY INVISIBLE (-1325 3510);
WIRE 16 -1 (-1325 2050)(550 2050);
FORCEPROP 2 LAST SIG_NAME SATA6G_P6_TX_C_DP
J 0
(-1085 2060);
DISPLAY 0.617021 (-1085 2060);
PAINT ORANGE (-1085 2060);
FORCEPROP 2 LASTPROP $XRERR UNIQUE?
J 0
(-1325 2060);
DISPLAY 0.638298 (-1325 2060);
PAINT MONO (-1325 2060);
DISPLAY INVISIBLE (-1325 2060);
WIRE 16 -1 (-2725 4350)(-4075 4350);
FORCEPROP 2 LAST SIG_NAME SATA6G_P0_RX_C_DN
J 0
(-3500 4360);
DISPLAY 0.617021 (-3500 4360);
PAINT ORANGE (-3500 4360);
FORCEPROP 2 LASTPROP $XRERR UNIQUE?
J 0
(-3740 4360);
DISPLAY 0.638298 (-3740 4360);
PAINT MONO (-3740 4360);
DISPLAY INVISIBLE (-3740 4360);
WIRE 16 -1 (-4075 4400)(-4075 4350);
WIRE 16 -1 (-4750 4400)(-4075 4400);
WIRE 16 -1 (-3900 3750)(-2725 3750);
FORCEPROP 2 LAST SIG_NAME PU_DATAIN1_SATA_0_R
J 0
(-3500 3750);
DISPLAY 0.617021 (-3500 3750);
PAINT ORANGE (-3500 3750);
FORCEPROP 2 LASTPROP $XRERR UNIQUE?
J 0
(-3740 3750);
DISPLAY 0.638298 (-3740 3750);
PAINT MONO (-3740 3750);
DISPLAY INVISIBLE (-3740 3750);
WIRE 16 -1 (-3900 4575)(-3900 3750);
WIRE 16 -1 (-1325 3900)(-50 3900);
FORCEPROP 2 LAST SIG_NAME SGPIO_PCH_SATA_CLOCK_R
J 0
(-1085 3910);
DISPLAY 0.617021 (-1085 3910);
PAINT ORANGE (-1085 3910);
WIRE 16 -1 (-1325 3850)(-50 3850);
FORCEPROP 2 LAST SIG_NAME SGPIO_PCH_SATA_LOAD_R
J 0
(-1085 3860);
DISPLAY 0.617021 (-1085 3860);
PAINT ORANGE (-1085 3860);
WIRE 16 -1 (-475 2350)(-1325 2350);
FORCEPROP 2 LAST SIG_NAME TP_SGPIO_SATA_LOAD1_R
J 0
(-1085 2360);
DISPLAY 0.617021 (-1085 2360);
PAINT ORANGE (-1085 2360);
FORCEPROP 2 LASTPROP $XRERR UNIQUE?
J 0
(-445 2350);
DISPLAY 0.638298 (-445 2350);
PAINT MONO (-445 2350);
DISPLAY INVISIBLE (-445 2350);
WIRE 16 -1 (-475 2400)(-1325 2400);
FORCEPROP 2 LAST SIG_NAME TP_SGPIO_SATA_CLOCK1_R
J 0
(-1085 2410);
DISPLAY 0.617021 (-1085 2410);
PAINT ORANGE (-1085 2410);
FORCEPROP 2 LASTPROP $XRERR UNIQUE?
J 0
(-445 2400);
DISPLAY 0.638298 (-445 2400);
PAINT MONO (-445 2400);
DISPLAY INVISIBLE (-445 2400);
WIRE 16 -1 (-3525 3800)(-2725 3800);
FORCEPROP 2 LAST SIG_NAME SGPIO_PCH_SATA_DOUT0_R
J 0
(-3500 3810);
DISPLAY 0.617021 (-3500 3810);
PAINT ORANGE (-3500 3810);
WIRE 16 -1 (-2725 2300)(-3575 2300);
FORCEPROP 2 LAST SIG_NAME TP_SGPIO_SATA_DATA1_R
J 0
(-3500 2310);
DISPLAY 0.617021 (-3500 2310);
PAINT ORANGE (-3500 2310);
FORCEPROP 2 LASTPROP $XRERR UNIQUE?
J 0
(-3815 2300);
DISPLAY 0.638298 (-3815 2300);
PAINT MONO (-3815 2300);
DISPLAY INVISIBLE (-3815 2300);
WIRE 16 -1 (-2725 2400)(-3575 2400);
FORCEPROP 2 LAST SIG_NAME TP_FM_QAT_CBL_PRSNT1_N_R
J 0
(-3500 2410);
DISPLAY 0.617021 (-3500 2410);
PAINT ORANGE (-3500 2410);
FORCEPROP 2 LASTPROP $XRERR UNIQUE?
J 0
(-3815 2400);
DISPLAY 0.638298 (-3815 2400);
PAINT MONO (-3815 2400);
DISPLAY INVISIBLE (-3815 2400);
WIRE 16 -1 (-3525 3900)(-2725 3900);
FORCEPROP 2 LAST SIG_NAME TP_FM_QAT_CBL_PRSNT0_R_N
J 0
(-3500 3910);
DISPLAY 0.617021 (-3500 3910);
PAINT ORANGE (-3500 3910);
FORCEPROP 2 LASTPROP $XRERR UNIQUE?
J 0
(-3765 3900);
DISPLAY 0.638298 (-3765 3900);
PAINT MONO (-3765 3900);
DISPLAY INVISIBLE (-3765 3900);
WIRE 16 -1 (-3550 2200)(-3800 2200);
WIRE 16 -1 (-3550 2250)(-3550 2200);
WIRE 16 -1 (-2725 2250)(-3550 2250);
FORCEPROP 2 LAST SIG_NAME PU_DATAIN1_SATA_1_R
J 0
(-3500 2260);
DISPLAY 0.617021 (-3500 2260);
PAINT ORANGE (-3500 2260);
FORCEPROP 2 LASTPROP $XRERR UNIQUE?
J 0
(-3740 2260);
DISPLAY 0.638298 (-3740 2260);
PAINT MONO (-3740 2260);
DISPLAY INVISIBLE (-3740 2260);
WIRE 16 -1 (-2725 2600)(-3925 2600);
FORCEPROP 2 LAST SIG_NAME SATA6G_P5_RX_C_DN
J 0
(-3500 2610);
DISPLAY 0.617021 (-3500 2610);
PAINT ORANGE (-3500 2610);
FORCEPROP 2 LASTPROP $XRERR UNIQUE?
J 0
(-3740 2610);
DISPLAY 0.638298 (-3740 2610);
PAINT MONO (-3740 2610);
DISPLAY INVISIBLE (-3740 2610);
WIRE 16 -1 (-3925 2400)(-3925 2600);
WIRE 16 -1 (-4850 2400)(-3925 2400);
WIRE 16 -1 (-2725 2650)(-4050 2650);
FORCEPROP 2 LAST SIG_NAME SATA6G_P5_RX_C_DP
J 0
(-3500 2660);
DISPLAY 0.617021 (-3500 2660);
PAINT ORANGE (-3500 2660);
FORCEPROP 2 LASTPROP $XRERR UNIQUE?
J 0
(-3740 2660);
DISPLAY 0.638298 (-3740 2660);
PAINT MONO (-3740 2660);
DISPLAY INVISIBLE (-3740 2660);
WIRE 16 -1 (-4050 2550)(-4050 2650);
WIRE 16 -1 (-4475 2550)(-4050 2550);
WIRE 16 -1 (-4500 2900)(-2725 2900);
FORCEPROP 2 LAST SIG_NAME SATA6G_P4_RX_C_DP
J 0
(-3500 2910);
DISPLAY 0.617021 (-3500 2910);
PAINT ORANGE (-3500 2910);
FORCEPROP 2 LASTPROP $XRERR UNIQUE?
J 0
(-3740 2910);
DISPLAY 0.638298 (-3740 2910);
PAINT MONO (-3740 2910);
DISPLAY INVISIBLE (-3740 2910);
WIRE 16 -1 (-2725 4150)(-4225 4150);
FORCEPROP 2 LAST SIG_NAME SATA6G_P1_RX_C_DP
J 0
(-3500 4160);
DISPLAY 0.617021 (-3500 4160);
PAINT ORANGE (-3500 4160);
FORCEPROP 2 LASTPROP $XRERR UNIQUE?
J 0
(-3740 4160);
DISPLAY 0.638298 (-3740 4160);
PAINT MONO (-3740 4160);
DISPLAY INVISIBLE (-3740 4160);
WIRE 16 -1 (-4225 4200)(-4225 4150);
WIRE 16 -1 (-4475 4200)(-4225 4200);
WIRE 16 -1 (-4675 4200)(-5350 4200);
WIRE 16 -1 (-4675 4550)(-5350 4550);
WIRE 16 -1 (-4950 4400)(-5200 4400);
WIRE 16 -1 (-2725 3300)(-4275 3300);
FORCEPROP 2 LAST SIG_NAME SATA6G_P3_RX_C_DP
J 0
(-3500 3310);
DISPLAY 0.617021 (-3500 3310);
PAINT ORANGE (-3500 3310);
FORCEPROP 2 LASTPROP $XRERR UNIQUE?
J 0
(-3740 3310);
DISPLAY 0.638298 (-3740 3310);
PAINT MONO (-3740 3310);
DISPLAY INVISIBLE (-3740 3310);
WIRE 16 -1 (-4275 3350)(-4475 3350);
WIRE 16 -1 (-4275 3350)(-4275 3300);
WIRE 16 -1 (-2725 2850)(-4150 2850);
FORCEPROP 2 LAST SIG_NAME SATA6G_P4_RX_C_DN
J 0
(-3500 2860);
DISPLAY 0.617021 (-3500 2860);
PAINT ORANGE (-3500 2860);
FORCEPROP 2 LASTPROP $XRERR UNIQUE?
J 0
(-3740 2860);
DISPLAY 0.638298 (-3740 2860);
PAINT MONO (-3740 2860);
DISPLAY INVISIBLE (-3740 2860);
WIRE 16 -1 (-4150 2750)(-4150 2850);
WIRE 16 -1 (-4850 2750)(-4150 2750);
WIRE 16 -1 (-5200 4050)(-4950 4050);
WIRE 16 -1 (-4675 2550)(-5350 2550);
WIRE 16 -1 (-5200 2400)(-5050 2400);
WIRE 16 -1 (-4675 3350)(-5350 3350);
WIRE 16 -1 (-5200 3200)(-5000 3200);
WIRE 16 -1 (-4675 3700)(-5350 3700);
WIRE 16 -1 (-5050 2750)(-5200 2750);
WIRE 16 -1 (-4675 2050)(-5350 2050);
WIRE 16 -1 (-5075 1850)(-5200 1850);
WIRE 16 -1 (-5200 1500)(-5075 1500);
WIRE 16 -1 (-4675 1700)(-5350 1700);
WIRE 16 -1 (-1325 3300)(525 3300);
FORCEPROP 2 LAST SIG_NAME SATA6G_P3_TX_C_DP
J 0
(-1085 3310);
DISPLAY 0.617021 (-1085 3310);
PAINT ORANGE (-1085 3310);
FORCEPROP 2 LASTPROP $XRERR UNIQUE?
J 0
(-1325 3310);
DISPLAY 0.638298 (-1325 3310);
PAINT MONO (-1325 3310);
DISPLAY INVISIBLE (-1325 3310);
WIRE 16 -1 (-225 3250)(-1325 3250);
WIRE 16 -1 (-225 3075)(-225 3250);
FORCEPROP 2 LAST SIG_NAME SATA6G_P3_TX_C_DN
J 0
(-1085 3260);
DISPLAY 0.617021 (-1085 3260);
PAINT ORANGE (-1085 3260);
FORCEPROP 2 LASTPROP $XRERR UNIQUE?
J 0
(-1325 3260);
DISPLAY 0.638298 (-1325 3260);
PAINT MONO (-1325 3260);
DISPLAY INVISIBLE (-1325 3260);
WIRE 16 -1 (-225 3075)(925 3075);
WIRE 16 -1 (-1325 2000)(-275 2000);
FORCEPROP 2 LAST SIG_NAME SATA6G_P6_TX_C_DN
J 0
(-1085 2010);
DISPLAY 0.617021 (-1085 2010);
PAINT ORANGE (-1085 2010);
FORCEPROP 2 LASTPROP $XRERR UNIQUE?
J 0
(-1325 2010);
DISPLAY 0.638298 (-1325 2010);
PAINT MONO (-1325 2010);
DISPLAY INVISIBLE (-1325 2010);
WIRE 16 -1 (-275 1900)(-275 2000);
WIRE 16 -1 (-275 1900)(950 1900);
WIRE 16 -1 (-400 2350)(925 2350);
WIRE 16 -1 (-400 2350)(-400 2600);
WIRE 16 -1 (-1325 2600)(-400 2600);
FORCEPROP 2 LAST SIG_NAME SATA6G_P5_TX_C_DN
J 0
(-1085 2610);
DISPLAY 0.617021 (-1085 2610);
PAINT ORANGE (-1085 2610);
FORCEPROP 2 LASTPROP $XRERR UNIQUE?
J 0
(-1325 2610);
DISPLAY 0.638298 (-1325 2610);
PAINT MONO (-1325 2610);
DISPLAY INVISIBLE (-1325 2610);
WIRE 16 -1 (750 1700)(1400 1700);
WIRE 16 -1 (-250 2650)(-1325 2650);
WIRE 16 -1 (-250 2500)(-250 2650);
FORCEPROP 0 LAST SIG_NAME SATA6G_P5_TX_C_DP
J 0
(-1085 2660);
DISPLAY 0.617021 (-1085 2660);
PAINT ORANGE (-1085 2660);
FORCEPROP 2 LASTPROP $XRERR UNIQUE?
J 0
(-1325 2660);
DISPLAY 0.638298 (-1325 2660);
PAINT MONO (-1325 2660);
DISPLAY INVISIBLE (-1325 2660);
WIRE 16 -1 (-250 2500)(550 2500);
WIRE 16 -1 (750 2500)(1400 2500);
WIRE 16 -1 (-475 4675)(550 4675);
WIRE 16 -1 (-475 4675)(-475 4400);
WIRE 16 -1 (-1325 4400)(-475 4400);
FORCEPROP 2 LAST SIG_NAME SATA6G_P0_TX_C_DP
J 0
(-1085 4410);
DISPLAY 0.617021 (-1085 4410);
PAINT ORANGE (-1085 4410);
FORCEPROP 2 LASTPROP $XRERR UNIQUE?
J 0
(-1325 4410);
DISPLAY 0.638298 (-1325 4410);
PAINT MONO (-1325 4410);
DISPLAY INVISIBLE (-1325 4410);
WIRE 16 -1 (925 4175)(-175 4175);
WIRE 16 -1 (-175 4175)(-175 4100);
WIRE 16 -1 (-1325 4100)(-175 4100);
FORCEPROP 2 LAST SIG_NAME SATA6G_P1_TX_C_DN
J 0
(-1085 4110);
DISPLAY 0.617021 (-1085 4110);
PAINT ORANGE (-1085 4110);
FORCEPROP 2 LASTPROP $XRERR UNIQUE?
J 0
(-1325 4110);
DISPLAY 0.638298 (-1325 4110);
PAINT MONO (-1325 4110);
DISPLAY INVISIBLE (-1325 4110);
WIRE 16 -1 (725 3650)(1400 3650);
WIRE 16 -1 (-425 1800)(-1325 1800);
WIRE 16 -1 (-425 1700)(-425 1800);
FORCEPROP 2 LAST SIG_NAME SATA6G_P7_TX_C_DP
J 0
(-1085 1810);
DISPLAY 0.617021 (-1085 1810);
PAINT ORANGE (-1085 1810);
FORCEPROP 2 LASTPROP $XRERR UNIQUE?
J 0
(-1325 1810);
DISPLAY 0.638298 (-1325 1810);
PAINT MONO (-1325 1810);
DISPLAY INVISIBLE (-1325 1810);
WIRE 16 -1 (-425 1700)(550 1700);
WIRE 16 -1 (-4875 1500)(-3825 1500);
WIRE 16 -1 (-3825 1500)(-3825 1750);
WIRE 16 -1 (-2725 1750)(-3825 1750);
FORCEPROP 2 LAST SIG_NAME SATA6G_P7_RX_C_DN
J 0
(-3500 1760);
DISPLAY 0.617021 (-3500 1760);
PAINT ORANGE (-3500 1760);
FORCEPROP 2 LASTPROP $XRERR UNIQUE?
J 0
(-3740 1760);
DISPLAY 0.638298 (-3740 1760);
PAINT MONO (-3740 1760);
DISPLAY INVISIBLE (-3740 1760);
WIRE 16 -1 (-4700 2900)(-5350 2900);
WIRE 16 -1 (-2725 2000)(-4125 2000);
FORCEPROP 2 LAST SIG_NAME SATA6G_P6_RX_C_DN
J 0
(-3500 2010);
DISPLAY 0.617021 (-3500 2010);
PAINT ORANGE (-3500 2010);
FORCEPROP 2 LASTPROP $XRERR UNIQUE?
J 0
(-3740 2010);
DISPLAY 0.638298 (-3740 2010);
PAINT MONO (-3740 2010);
DISPLAY INVISIBLE (-3740 2010);
WIRE 16 -1 (-4125 1850)(-4125 2000);
WIRE 16 -1 (-4875 1850)(-4125 1850);
WIRE 16 -1 (-5000 3550)(-5200 3550);
WIRE 16 273 (-5150 1275)(-4375 1275);
WIRE 16 273 (-5150 4725)(-5150 1275);
WIRE 16 273 (-4375 4725)(-4375 1275);
WIRE 16 273 (-4375 4725)(-5150 4725);
WIRE 16 -1 (-4475 2050)(-2725 2050);
FORCEPROP 2 LAST SIG_NAME SATA6G_P6_RX_C_DP
J 0
(-3500 2060);
DISPLAY 0.617021 (-3500 2060);
PAINT ORANGE (-3500 2060);
FORCEPROP 2 LASTPROP $XRERR UNIQUE?
J 0
(-3740 2060);
DISPLAY 0.638298 (-3740 2060);
PAINT MONO (-3740 2060);
DISPLAY INVISIBLE (-3740 2060);
WIRE 16 -1 (-1325 3550)(-500 3550);
FORCEPROP 2 LAST SIG_NAME SATA6G_P2_TX_C_DP
J 0
(-1085 3560);
DISPLAY 0.617021 (-1085 3560);
PAINT ORANGE (-1085 3560);
FORCEPROP 2 LASTPROP $XRERR UNIQUE?
J 0
(-1325 3560);
DISPLAY 0.638298 (-1325 3560);
PAINT MONO (-1325 3560);
DISPLAY INVISIBLE (-1325 3560);
WIRE 16 -1 (-500 3650)(-500 3550);
WIRE 16 -1 (-500 3650)(525 3650);
WIRE 16 -1 (1675 3750)(1675 3600);
WIRE 16 -1 (-1325 3750)(1675 3750);
FORCEPROP 2 LAST SIG_NAME PD_SATA0_CONTROLLER_TYPE_R
J 0
(-1085 3760);
DISPLAY 0.617021 (-1085 3760);
PAINT ORANGE (-1085 3760);
FORCEPROP 2 LASTPROP $XRERR UNIQUE?
J 0
(-1325 3760);
DISPLAY 0.638298 (-1325 3760);
PAINT MONO (-1325 3760);
DISPLAY INVISIBLE (-1325 3760);
WIRE 16 -1 (-1325 4350)(-425 4350);
FORCEPROP 2 LAST SIG_NAME SATA6G_P0_TX_C_DN
J 0
(-1085 4360);
DISPLAY 0.617021 (-1085 4360);
PAINT ORANGE (-1085 4360);
FORCEPROP 2 LASTPROP $XRERR UNIQUE?
J 0
(-1325 4360);
DISPLAY 0.638298 (-1325 4360);
PAINT MONO (-1325 4360);
DISPLAY INVISIBLE (-1325 4360);
WIRE 16 -1 (-425 4525)(-425 4350);
WIRE 16 -1 (-425 4525)(925 4525);
WIRE 16 -1 (-4800 3200)(-4275 3200);
FORCEPROP 2 LAST SIG_NAME SATA6G_P3_RX_C_DN
J 0
(-3500 3260);
DISPLAY 0.617021 (-3500 3260);
PAINT ORANGE (-3500 3260);
FORCEPROP 2 LASTPROP $XRERR UNIQUE?
J 0
(-3740 3260);
DISPLAY 0.638298 (-3740 3260);
PAINT MONO (-3740 3260);
DISPLAY INVISIBLE (-3740 3260);
WIRE 16 -1 (-4275 3200)(-4275 3250);
WIRE 16 -1 (-4275 3250)(-2725 3250);
WIRE 16 -1 (-4800 3550)(-4250 3550);
WIRE 16 -1 (-4250 3550)(-4250 3500);
WIRE 16 -1 (-2725 3500)(-4250 3500);
FORCEPROP 2 LAST SIG_NAME SATA6G_P2_RX_C_DN
J 0
(-3500 3510);
DISPLAY 0.617021 (-3500 3510);
PAINT ORANGE (-3500 3510);
FORCEPROP 2 LASTPROP $XRERR UNIQUE?
J 0
(-3740 3510);
DISPLAY 0.638298 (-3740 3510);
PAINT MONO (-3740 3510);
DISPLAY INVISIBLE (-3740 3510);
WIRE 16 273 (1200 1325)(1200 4825);
WIRE 16 273 (1200 4825)(425 4825);
WIRE 16 273 (425 1325)(1200 1325);
WIRE 16 273 (425 1325)(425 4825);
WIRE 16 -1 (-225 4325)(550 4325);
WIRE 16 -1 (-225 4325)(-225 4150);
WIRE 16 -1 (-1325 4150)(-225 4150);
FORCEPROP 2 LAST SIG_NAME SATA6G_P1_TX_C_DP
J 0
(-1085 4160);
DISPLAY 0.617021 (-1085 4160);
PAINT ORANGE (-1085 4160);
FORCEPROP 2 LASTPROP $XRERR UNIQUE?
J 0
(-1325 4160);
DISPLAY 0.638298 (-1325 4160);
PAINT MONO (-1325 4160);
DISPLAY INVISIBLE (-1325 4160);
WIRE 16 -1 (-2725 4400)(-3975 4400);
FORCEPROP 2 LAST SIG_NAME SATA6G_P0_RX_C_DP
J 0
(-3500 4400);
DISPLAY 0.617021 (-3500 4400);
PAINT ORANGE (-3500 4400);
FORCEPROP 2 LASTPROP $XRERR UNIQUE?
J 0
(-3740 4400);
DISPLAY 0.638298 (-3740 4400);
PAINT MONO (-3740 4400);
DISPLAY INVISIBLE (-3740 4400);
WIRE 16 -1 (-3975 4550)(-3975 4400);
WIRE 16 -1 (-4475 4550)(-3975 4550);
WIRE 16 -1 (750 4325)(1400 4325);
WIRE 16 -1 (-1325 2850)(-250 2850);
FORCEPROP 2 LAST SIG_NAME SATA6G_P4_TX_C_DN
J 0
(-1085 2860);
DISPLAY 0.617021 (-1085 2860);
PAINT ORANGE (-1085 2860);
FORCEPROP 2 LASTPROP $XRERR UNIQUE?
J 0
(-1325 2860);
DISPLAY 0.638298 (-1325 2860);
PAINT MONO (-1325 2860);
DISPLAY INVISIBLE (-1325 2860);
WIRE 16 -1 (-250 2725)(-250 2850);
WIRE 16 -1 (-250 2725)(925 2725);
WIRE 16 -1 (-4475 3700)(-4100 3700);
WIRE 16 -1 (-4100 3700)(-4100 3550);
WIRE 16 -1 (-2725 3550)(-4100 3550);
FORCEPROP 2 LAST SIG_NAME SATA6G_P2_RX_C_DP
J 0
(-3500 3560);
DISPLAY 0.617021 (-3500 3560);
PAINT ORANGE (-3500 3560);
FORCEPROP 2 LASTPROP $XRERR UNIQUE?
J 0
(-3740 3560);
DISPLAY 0.638298 (-3740 3560);
PAINT MONO (-3740 3560);
DISPLAY INVISIBLE (-3740 3560);
DOT 1 (-2925 2500);
DOT 1 (-2925 1650);
DOT 1 (-1150 1650);
DOT 1 (-2925 1900);
DOT 1 (-1150 1900);
DOT 1 (-2925 2150);
DOT 1 (-1150 2150);
DOT 1 (-1150 2300);
DOT 1 (-2925 2350);
DOT 1 (-1150 2500);
DOT 1 (-2925 2750);
DOT 1 (-1150 2750);
DOT 1 (-2925 3000);
DOT 1 (-1150 3000);
DOT 1 (-2925 3150);
DOT 1 (-1150 3150);
DOT 1 (-2925 3400);
DOT 1 (-1150 3400);
DOT 1 (-2925 3650);
DOT 1 (-1150 3650);
DOT 1 (-2925 3850);
DOT 1 (-2925 4000);
DOT 1 (-1150 4000);
DOT 1 (-2925 4250);
DOT 1 (-1150 4250);
DOT 1 (-1150 3800);
FORCENOTE
VERTICAL MINI-SAS
(-2300 4900) 0;
DISPLAY LEFT (-2300 4900);
DISPLAY 1.021277 (-2300 4900);
PAINT PURPLE (-2300 4900);
FORCENOTE
BOM_COST=ST_SATA
(-5825 700) 0;
DISPLAY LEFT (-5825 700);
DISPLAY 2.148936 (-5825 700);
PAINT PURPLE (-5825 700);
FORCENOTE
ROOM=ST_SATA
(-5825 825) 0;
DISPLAY LEFT (-5825 825);
DISPLAY 2.148936 (-5825 825);
PAINT PURPLE (-5825 825);
QUIT
